FILE_TYPE = MULTI_PHYS_TABLE;

PART 'RESISTOR'
CLASS=DISCRETE

{========================================================================================}
:CLS_PN          | VALUE        | TOLERANCE    = JEDEC_TYPE           | ALT_SYMBOLS                            | DESCRIPTION                                                                             | CPN_STATUS ;
{========================================================================================}
 'CL100697A'     | '1MOHM'      | '5%'         = 'SMC_0603R'          | '(SMC_0603R)'                          | 'RESISTOR, SINGLE,1MOHM,THICK FILM,5%,50V,.1W, ,-55/125C,0603'                          | 'NFND'    
 'CL100698A'     | '10MOHM'     | '5%'         = 'SMC_0603R'          | '(SMC_0603R)'                          | 'RESISTOR, SINGLE,10MOHM,THICK FILM,5%,50V,.1W,-55/125C,0603'                           | 'NFND'    
 'CL100699A'     | '1OHM'       | '5%'         = 'SMC_0603R'          | '(SMC_0603R)'                          | 'RESISTOR, SINGLE,1OHM,THICK FILM,5%,50V,.1W,-55/125C,0603'                             | 'NFND'    
 'CL100700A'     | '1.2OHM'     | '5%'         = 'SMC_0603R'          | '(SMC_0603R)'                          | 'RESISTOR, SINGLE,1.2OHM,THICK FILM,5%,50V,.1W,-55/125C,0603'                           | 'NFND'    
 'G156-001R2-05' | '1.2OHM'     | '5%'         = 'SMC_0603R'          | '(SMC_0603R)'                          | 'RESISTOR, SINGLE,1.2OHM,THICK FILM,5%,50V,.1W,-55/125C,0603'                           | ''        
 'CL100701A'     | '1.8OHM'     | '5%'         = 'SMC_0603R'          | '(SMC_0603R)'                          | 'RESISTOR, SINGLE,1.8OHM,THICK FILM,5%,50V,.1W,-55/125C,0603'                           | 'NFND'    
 'CL100702A'     | '2.2MOHM'    | '5%'         = 'SMC_0603R'          | '(SMC_0603R)'                          | 'RESISTOR, SINGLE,2.2MOHM,THICK FILM,5%,50V,.1W,-55/125C,0603'                          | 'NFND'    
 'CL100703A'     | '3.3MOHM'    | '5%'         = 'SMC_0603R'          | '(SMC_0603R)'                          | 'RESISTOR, SINGLE,3.3MOHM,THICK FILM,5%,50V,.1W,-55/125C,0603'                          | 'NFND'    
 'CL100704A'     | '6.8OHM'     | '5%'         = 'SMC_0603R'          | '(SMC_0603R)'                          | 'RESISTOR, SINGLE,6.8OHM,THICK FILM,5%,50V,.1W,-55/125C,0603'                           | 'NFND'    
 'CL100705A'     | '4.7OHM'     | '5%'         = 'SMC_0603R'          | '(SMC_0603R)'                          | 'RESISTOR, SINGLE,4.7OHM,THICK FILM,5%,50V,.1W,-55/125C,0603'                           | 'NFND'    
 'G156-004R7-05' | '4.7OHM'     | '5%'         = 'SMC_0603R'          | '(SMC_0603R)'                          | 'RESISTOR, SINGLE,4.7OHM,THICK FILM,5%,50V,.1W,-55/125C,0603'                           | ''        
 'CL100706A'     | '1OHM'       | '5%'         = 'SMC_1206R'          | '(SMC_1206R)'                          | 'RESISTOR, SINGLE,1OHM,THICK FILM,5%,200V,.25W,-55/125C,1206'                           | 'NFND'    
 'CL100707A'     | '3.3OHM'     | '5%'         = 'SMC_1206R'          | '(SMC_1206R)'                          | 'RESISTOR, SINGLE,3.3OHM,THICK FILM,5%,200V,.25W,-55/125C,1206'                         | 'NFND'    
 'CL100708A'     | '1.8OHM'     | '5%'         = 'SMC_1206R'          | '(SMC_1206R)'                          | 'RESISTOR, SINGLE,1.8OHM,THICK FILM,5%,200V,.25W,-55/125C,1206'                         | 'NFND'    
 'CL100709A'     | '2.2OHM'     | '5%'         = 'SMC_1206R'          | '(SMC_1206R)'                          | 'RESISTOR, SINGLE,2.2OHM,THICK FILM,5%,200V,.25W,-55/125C,1206'                         | ''        
 'CL100710A'     | '10OHM'      | '1%'         = 'SMC_0402R'          | '(SMC_0402R_C)'                        | 'RESISTOR, SINGLE,10OHM,THICK FILM,1%,50V,.063W,-55/125C,SMD,0402'                      | 'NFND'    
 'G152-00032-01' | '10OHM'      | '1%'         = 'SMC_0402R'          | '(SMC_0402R_C)'                        | 'RESISTOR, SINGLE,10OHM,THICK FILM,1%,50V,.063W,-55/125C,SMD,0402'                      | ''        
 'CL100711A'     | '100OHM'     | '1%'         = 'SMC_0402R'          | '(SMC_0402R_C)'                        | 'RESISTOR, SINGLE,100OHM,THICK FILM,1%,50V,.063W,-55/125C,0402'                         | 'NFND'    
 'G152-00044-01' | '100OHM'     | '1%'         = 'SMC_0402R'          | '(SMC_0402R_C)'                        | 'RESISTOR, SINGLE,100OHM,THICK FILM,1%,50V,.063W,-55/125C,0402'                         | ''        
 'CL100712A'     | '1KOHM'      | '1%'         = 'SMC_0402R'          | '(SMC_0402R_C)'                        | 'RESISTOR, SINGLE,1KOHM,THICK FILM,1%,50V,.063W,-55/125C,0402'                          | 'NFND'    
 'G152-00031-01' | '1KOHM'      | '1%'         = 'SMC_0402R'          | '(SMC_0402R_C)'                        | 'RESISTOR, SINGLE,1KOHM,THICK FILM,1%,50V,.063W,-55/125C,0402'                          | 'NFND'    
 'CL100715A'     | '1MOHM'      | '1%'         = 'SMC_0402R'          | '(SMC_0402R_C)'                        | 'RESISTOR, SINGLE,1MOHM,THICK FILM,1%,50V,.063W,-55/125C,0402'                          | 'NFND'    
 'G152-00045-01' | '1MOHM'      | '1%'         = 'SMC_0402R'          | '(SMC_0402R_C)'                        | 'RESISTOR, SINGLE,1MOHM,THICK FILM,1%,50V,.063W,-55/125C,0402'                          | ''        
 'CL100716A'     | '1.1KOHM'    | '1%'         = 'SMC_0402R'          | '(SMC_0402R_C)'                        | 'RESISTOR, SINGLE,1.1KOHM,THICK FILM,1%,50V,.063W,-55/125C,0402'                        | 'NFND'    
 'CL100717A'     | '11KOHM'     | '1%'         = 'SMC_0402R'          | '(SMC_0402R_C)'                        | 'RESISTOR, SINGLE,11KOHM,THICK FILM,1%,.063W,-55/125C,0402'                             | 'NFND'    
 'CL100718A'     | '11.5OHM'    | '1%'         = 'SMC_0402R'          | '(SMC_0402R_C)'                        | 'RESISTOR, SINGLE,11.5OHM,THICK FILM,1%,50V,.063W,-55/125C,0402'                        | 'NFND'    
 'CL100719A'     | '121OHM'     | '1%'         = 'SMC_0402R'          | '(SMC_0402R_C)'                        | 'RESISTOR, SINGLE,121OHM,THICK FILM,1%,50V,.063W,-55/125C,0402'                         | 'NFND'    
 'CL100720A'     | '133OHM'     | '1%'         = 'SMC_0402R'          | '(SMC_0402R_C)'                        | 'RESISTOR, SINGLE,133OHM,THICK FILM,1%,50V,.063W,-55/125C,0402'                         | 'NFND'    
 'G152-00030-01' | '133OHM'     | '1%'         = 'SMC_0402R'          | '(SMC_0402R_C)'                        | 'RESISTOR, SINGLE,133OHM,THICK FILM,1%,50V,.063W,-55/125C,0402'                         | ''        
 'CL100721A'     | '1.33KOHM'   | '1%'         = 'SMC_0402R'          | '(SMC_0402R_C)'                        | 'RESISTOR, SINGLE,1.33KOHM,THICK FILM,1%,50V,.063W,-55/125C,0402'                       | 'NFND'    
 'CL100722A'     | '147OHM'     | '1%'         = 'SMC_0402R'          | '(SMC_0402R_C)'                        | 'RESISTOR, SINGLE,147OHM,THICK FILM,1%,50V,.063W,-55/125C,0402'                         | 'NFND'    
 'CL100723A'     | '1.47KOHM'   | '1%'         = 'SMC_0402R'          | '(SMC_0402R_C)'                        | 'RESISTOR, SINGLE,1.47KOHM,THICK FILM,1%,50V,.063W,-55/125C,0402'                       | 'NFND'    
 'CL100724A'     | '14.7KOHM'   | '1%'         = 'SMC_0402R'          | '(SMC_0402R_C)'                        | 'RESISTOR, SINGLE,14.7KOHM,THICK FILM,1%,50V,.063W,-55/125C,0402'                       | 'NFND'    
 'CL100725A'     | '162OHM'     | '1%'         = 'SMC_0402R'          | '(SMC_0402R_C)'                        | 'RESISTOR, SINGLE,162OHM,THICK FILM,1%,50V,.063W,-55/125C,0402'                         | 'NFND'    
 'CL100726A'     | '1.62KOHM'   | '1%'         = 'SMC_0402R'          | '(SMC_0402R_C)'                        | 'RESISTOR, SINGLE,1.62KOHM,THICK FILM,1%,50V,.063W,-55/125C,0402'                       | 'NFND'    
 'CL100727A'     | '1.78KOHM'   | '1%'         = 'SMC_0402R'          | '(SMC_0402R_C)'                        | 'RESISTOR, SINGLE,1.78KOHM,THICK FILM,1%,50V,.063W,-55/125C,0402'                       | 'NFND'    
 'CL100728A'     | '17.8KOHM'   | '1%'         = 'SMC_0402R'          | '(SMC_0402R_C)'                        | 'RESISTOR, SINGLE,17.8KOHM,THICK FILM,1%,50V,.063W,-55/125C,0402'                       | 'NFND'    
 'CL100729A'     | '187KOHM'    | '1%'         = 'SMC_0402R'          | '(SMC_0402R_C)'                        | 'RESISTOR, SINGLE,187KOHM,THICK FILM,1%,50V,.063W,-55/125C,0402'                        | 'NFND'    
 'CL100730A'     | '196OHM'     | '1%'         = 'SMC_0402R'          | '(SMC_0402R_C)'                        | 'RESISTOR, SINGLE,196OHM,THICK FILM,1%,50V,.063W,-55/125C,0402'                         | 'NFND'    
 'CL100731A'     | '1.96KOHM'   | '1%'         = 'SMC_0402R'          | '(SMC_0402R_C)'                        | 'RESISTOR, SINGLE,1.96KOHM,THICK FILM,1%,50V,.063W,-55/125C,0402'                       | 'NFND'    
 'CL100732A'     | '19.6KOHM'   | '1%'         = 'SMC_0402R'          | '(SMC_0402R_C)'                        | 'RESISTOR, SINGLE,19.6KOHM,THICK FILM,1%,50V,.063W,-55/125C,0402'                       | 'NFND'    
 'CL100733A'     | '19.6OHM'    | '1%'         = 'SMC_0402R'          | '(SMC_0402R_C)'                        | 'RESISTOR, SINGLE,19.6OHM,THICK FILM,1%,50V,.063W,-55/125C,0402'                        | 'NFND'    
 'CL100734A'     | '1OHM'       | '1%'         = 'SMC_0402R'          | '(SMC_0402R_C)'                        | 'RESISTOR, SINGLE,1OHM,THICK FILM,1%,50V,.063W,-55/125C,0402'                           | 'NFND'    
 'G152-00046-01' | '1OHM'       | '1%'         = 'SMC_0402R'          | '(SMC_0402R_C)'                        | 'RESISTOR, SINGLE,1OHM,THICK FILM,1%,50V,.063W,-55/125C,0402'                           | ''        
 'CL100735A'     | '215OHM'     | '1%'         = 'SMC_0402R'          | '(SMC_0402R_C)'                        | 'RESISTOR, SINGLE,215OHM,THICK FILM,1%,50V,.063W,-55/125C,0402'                         | 'NFND'    
 'CL100736A'     | '2.15KOHM'   | '1%'         = 'SMC_0402R'          | '(SMC_0402R_C)'                        | 'RESISTOR, SINGLE,2.15KOHM,THICK FILM,1%,50V,.063W,-55/125C,0402'                       | 'NFND'    
 'CL100737A'     | '21.5KOHM'   | '1%'         = 'SMC_0402R'          | '(SMC_0402R_C)'                        | 'RESISTOR, SINGLE,21.5KOHM,THICK FILM,1%,50V,.063W,-55/125C,0402'                       | 'NFND'    
 'CL100738A'     | '21.5OHM'    | '1%'         = 'SMC_0402R'          | '(SMC_0402R_C)'                        | 'RESISTOR, SINGLE,21.5OHM,THICK FILM,1%,50V,.063W,-55/125C,0402'                        | 'NFND'    
 'CL100739A'     | '237OHM'     | '1%'         = 'SMC_0402R'          | '(SMC_0402R_C)'                        | 'RESISTOR, SINGLE,237OHM,THICK FILM,1%,50V,.063W,-55/125C,0402'                         | 'NFND'    
 'CL100740A'     | '2.37KOHM'   | '1%'         = 'SMC_0402R'          | '(SMC_0402R_C)'                        | 'RESISTOR, SINGLE,2.37KOHM,THICK FILM,1%,50V,.063W,-55/125C,0402'                       | 'NFND'    
 'CL100742A'     | '24.9KOHM'   | '1%'         = 'SMC_0402R'          | '(SMC_0402R_C)'                        | 'RESISTOR, SINGLE,24.9KOHM,THICK FILM,1%,50V,.063W,-55/125C,0402'                       | 'NFND'    
 'CL100743A'     | '261OHM'     | '1%'         = 'SMC_0402R'          | '(SMC_0402R_C)'                        | 'RESISTOR, SINGLE,261OHM,THICK FILM,1%,50V,.063W,-55/125C,0402'                         | 'NFND'    
 'CL100744A'     | '2.61KOHM'   | '1%'         = 'SMC_0402R'          | '(SMC_0402R_C)'                        | 'RESISTOR, SINGLE,2.61KOHM,THICK FILM,1%,50V,.063W,-55/125C,0402'                       | 'NFND'    
 'CL100745A'     | '26.1KOHM'   | '1%'         = 'SMC_0402R'          | '(SMC_0402R_C)'                        | 'RESISTOR, SINGLE,26.1KOHM,THICK FILM,1%,50V,.063W,-55/125C,0402'                       | 'NFND'    
 'CL100746A'     | '26.1OHM'    | '1%'         = 'SMC_0402R'          | '(SMC_0402R_C)'                        | 'RESISTOR, SINGLE,26.1OHM,THICK FILM,1%,50V,.063W,-55/125C,0402'                        | 'NFND'    
 'CL100747A'     | '287OHM'     | '1%'         = 'SMC_0402R'          | '(SMC_0402R_C)'                        | 'RESISTOR, SINGLE,287OHM,THICK FILM,1%,50V,.063W,-55/125C,0402'                         | 'NFND'    
 'CL100748A'     | '2.87KOHM'   | '1%'         = 'SMC_0402R'          | '(SMC_0402R_C)'                        | 'RESISTOR, SINGLE,2.87KOHM,THICK FILM,1%,50V,.063W,-55/125C,0402'                       | 'NFND'    
 'CL100749A'     | '28.7KOHM'   | '1%'         = 'SMC_0402R'          | '(SMC_0402R_C)'                        | 'RESISTOR, SINGLE,28.7KOHM,THICK FILM,1%,50V,.063W,-55/125C,0402'                       | 'NFND'    
 'CL100750A'     | '316OHM'     | '1%'         = 'SMC_0402R'          | '(SMC_0402R_C)'                        | 'RESISTOR, SINGLE,316OHM,THICK FILM,1%,50V,.063W,-55/125C,0402'                         | 'NFND'    
 'CL100751A'     | '3.16KOHM'   | '1%'         = 'SMC_0402R'          | '(SMC_0402R_C)'                        | 'RESISTOR, SINGLE,3.16KOHM,THICK FILM,1%,50V,.063W,-55/125C,0402'                       | 'NFND'    
 'CL100752A'     | '31.6KOHM'   | '1%'         = 'SMC_0402R'          | '(SMC_0402R_C)'                        | 'RESISTOR, SINGLE,31.6KOHM,THICK FILM,1%,50V,.063W,-55/125C,0402'                       | 'NFND'    
 'CL100753A'     | '31.6OHM'    | '1%'         = 'SMC_0402R'          | '(SMC_0402R_C)'                        | 'RESISTOR, SINGLE,31.6OHM,THICK FILM,1%,50V,.063W,-55/125C,0402'                        | 'NFND'    
 'CL100754A'     | '332OHM'     | '1%'         = 'SMC_0402R'          | '(SMC_0402R_C)'                        | 'RESISTOR, SINGLE,332OHM,THICK FILM,1%,50V,.063W,-55/125C,0402'                         | 'NFND'    
 'CL100755A'     | '33.2KOHM'   | '1%'         = 'SMC_0402R'          | '(SMC_0402R_C)'                        | 'RESISTOR, SINGLE,33.2KOHM,THICK FILM,1%,50V,.063W,-55/125C,0402'                       | 'NFND'    
 'CL100756A'     | '3.48KOHM'   | '1%'         = 'SMC_0402R'          | '(SMC_0402R_C)'                        | 'RESISTOR, SINGLE,3.48KOHM,THICK FILM,1%,50V,.063W,-55/125C,0402'                       | 'NFND'    
 'CL100757A'     | '34.8OHM'    | '1%'         = 'SMC_0402R'          | '(SMC_0402R_C)'                        | 'RESISTOR, SINGLE,34.8OHM,THICK FILM,1%,50V,.063W,-55/125C,0402'                        | 'NFND'    
 'CL100758A'     | '3.65KOHM'   | '1%'         = 'SMC_0402R'          | '(SMC_0402R_C)'                        | 'RESISTOR, SINGLE,3.65KOHM,THICK FILM,1%,50V,.063W,-55/125C,0402'                       | 'NFND'    
 'CL100759A'     | '3.83KOHM'   | '1%'         = 'SMC_0402R'          | '(SMC_0402R_C)'                        | 'RESISTOR, SINGLE,3.83KOHM,THICK FILM,1%,50V,.063W,-55/125C,0402'                       | 'NFND'    
 'CL100760A'     | '38.3OHM'    | '1%'         = 'SMC_0402R'          | '(SMC_0402R_C)'                        | 'RESISTOR, SINGLE,38.3OHM,THICK FILM,1%,50V,.063W,-55/125C,0402'                        | 'NFND'    
 'CL100761A'     | '464OHM'     | '1%'         = 'SMC_0402R'          | '(SMC_0402R_C)'                        | 'RESISTOR, SINGLE,464OHM,THICK FILM,1%,50V,.063W,-55/125C,0402'                         | 'NFND'    
 'CL100762A'     | '4.64KOHM'   | '1%'         = 'SMC_0402R'          | '(SMC_0402R_C)'                        | 'RESISTOR, SINGLE,4.64KOHM,THICK FILM,1%,50V,.063W,-55/125C,0402'                       | 'NFND'    
 'CL100763A'     | '46.4KOHM'   | '1%'         = 'SMC_0402R'          | '(SMC_0402R_C)'                        | 'RESISTOR, SINGLE,46.4KOHM,THICK FILM,1%,50V,.063W,-55/125C,0402'                       | 'NFND'    
 'CL100764A'     | '511OHM'     | '1%'         = 'SMC_0402R'          | '(SMC_0402R_C)'                        | 'RESISTOR, SINGLE,511OHM,THICK FILM,1%,50V,.063W,-55/125C,0402'                         | 'NFND'    
 'CL100765A'     | '5.11KOHM'   | '1%'         = 'SMC_0402R'          | '(SMC_0402R_C)'                        | 'RESISTOR, SINGLE,5.11KOHM,THICK FILM,1%,50V,.063W,-55/125C,0402'                       | 'NFND'    
 'CL100766A'     | '51.1KOHM'   | '1%'         = 'SMC_0402R'          | '(SMC_0402R_C)'                        | 'RESISTOR, SINGLE,51.1KOHM,THICK FILM,1%,50V,.063W,-55/125C,0402'                       | 'NFND'    
 'CL100767A'     | '511KOHM'    | '1%'         = 'SMC_0402R'          | '(SMC_0402R_C)'                        | 'RESISTOR, SINGLE,511KOHM,THICK FILM,1%,50V,.063W,-55/125C,0402'                        | 'NFND'    
 'CL100768A'     | '51.1OHM'    | '1%'         = 'SMC_0402R'          | '(SMC_0402R_C)'                        | 'RESISTOR, SINGLE,51.1OHM,THICK FILM,1%,50V,.063W,-55/125C,0402'                        | 'NFND'    
 'G152-00057-01' | '51.1OHM'    | '1%'         = 'SMC_0402R'          | '(SMC_0402R_C)'                        | 'RESISTOR, SINGLE,51.1OHM,THICK FILM,1%,50V,.063W,-55/125C,0402'                        | ''        
 'CL100769A'     | '562OHM'     | '1%'         = 'SMC_0402R'          | '(SMC_0402R_C)'                        | 'RESISTOR, SINGLE,562OHM,THICK FILM,1%,50V,.063W,-55/125C,0402'                         | 'NFND'    
 'CL100770A'     | '5.62KOHM'   | '1%'         = 'SMC_0402R'          | '(SMC_0402R_C)'                        | 'RESISTOR, SINGLE,5.62KOHM,THICK FILM,1%,50V,.063W,-55/125C,0402'                       | 'NFND'    
 'CL100771A'     | '619OHM'     | '1%'         = 'SMC_0402R'          | '(SMC_0402R_C)'                        | 'RESISTOR, SINGLE,619OHM,THICK FILM,1%,50V,.063W,-55/125C,0402'                         | 'NFND'    
 'CL100772A'     | '6.19KOHM'   | '1%'         = 'SMC_0402R'          | '(SMC_0402R_C)'                        | 'RESISTOR, SINGLE,6.19KOHM,THICK FILM,1%,50V,.063W,-55/125C,0402'                       | 'NFND'    
 'CL100773A'     | '61.9KOHM'   | '1%'         = 'SMC_0402R'          | '(SMC_0402R_C)'                        | 'RESISTOR, SINGLE,61.9KOHM,THICK FILM,1%,50V,.063W,-55/125C,0402'                       | 'NFND'    
 'CL100774A'     | '61.9OHM'    | '1%'         = 'SMC_0402R'          | '(SMC_0402R_C)'                        | 'RESISTOR, SINGLE,61.9OHM,THICK FILM,1%,50V,.063W,-55/125C,0402'                        | 'NFND'    
 'CL100775A'     | '681OHM'     | '1%'         = 'SMC_0402R'          | '(SMC_0402R_C)'                        | 'RESISTOR, SINGLE,681OHM,THICK FILM,1%,50V,.063W,-55/125C,0402'                         | 'NFND'    
 'CL100776A'     | '6.81KOHM'   | '1%'         = 'SMC_0402R'          | '(SMC_0402R_C)'                        | 'RESISTOR, SINGLE,6.81KOHM,THICK FILM,1%,50V,.063W,-55/125C,0402'                       | 'NFND'    
 'CL100777A'     | '68.1KOHM'   | '1%'         = 'SMC_0402R'          | '(SMC_0402R_C)'                        | 'RESISTOR, SINGLE,68.1KOHM,THICK FILM,1%,50V,.063W,-55/125C,0402'                       | 'NFND'    
 'CL100778A'     | '68.1OHM'    | '1%'         = 'SMC_0402R'          | '(SMC_0402R_C)'                        | 'RESISTOR, SINGLE,68.1OHM,THICK FILM,1%,50V,.063W,-55/125C,SMD,0402'                    | 'NFND'    
 'CL100779A'     | '750OHM'     | '1%'         = 'SMC_0402R'          | '(SMC_0402R_C)'                        | 'RESISTOR, SINGLE,750OHM,THICK FILM,1%,50V,.063W,-55/125C,0402'                         | 'NFND'    
 'CL100780A'     | '7.5KOHM'    | '1%'         = 'SMC_0402R'          | '(SMC_0402R_C)'                        | 'RESISTOR, SINGLE,7.5KOHM,THICK FILM,1%,50V,.063W,-55/125C,0402'                        | 'NFND'    
 'CL100781A'     | '75OHM'      | '1%'         = 'SMC_0402R'          | '(SMC_0402R_C)'                        | 'RESISTOR, SINGLE,75OHM,THICK FILM,1%,50V,.063W,-55/125C,0402'                          | 'NFND'    
 'CL100782A'     | '8.25KOHM'   | '1%'         = 'SMC_0402R'          | '(SMC_0402R_C)'                        | 'RESISTOR, SINGLE,8.25KOHM,THICK FILM,1%,50V,.063W,-55/125C,0402'                       | 'NFND'    
 'CL100783A'     | '90.9KOHM'   | '1%'         = 'SMC_0402R'          | '(SMC_0402R_C)'                        | 'RESISTOR, SINGLE,90.9KOHM,THICK FILM,1%,50V,.063W,-55/125C,0402'                       | 'NFND'    
 'CL100784A'     | '90.9OHM'    | '1%'         = 'SMC_0402R'          | '(SMC_0402R_C)'                        | 'RESISTOR, SINGLE,90.9OHM,THICK FILM,1%,50V,.063W,-55/125C,0402'                        | 'NFND'    
 'CL100785A'     | '110OHM'     | '1%'         = 'SMC_0402R'          | '(SMC_0402R_C)'                        | 'RESISTOR, SINGLE,110OHM,THICK FILM,1%,50V,.063W,-55/125C,0402'                         | 'NFND'    
 'CL100786A'     | '100KOHM'    | '1%'         = 'SMC_0402R'          | '(SMC_0402R_C)'                        | 'RESISTOR, SINGLE,100KOHM,METAL FILM,1%,50V,.063W,-55/125C,SMD,0402'                    | 'NFND'    
 'G152-00029-01' | '100KOHM'    | '1%'         = 'SMC_0402R'          | '(SMC_0402R_C)'                        | 'RESISTOR, SINGLE,100KOHM,METAL FILM,1%,50V,.063W,-55/125C,SMD,0402'                    | ''        
 'CL100787A'     | '16.2OHM'    | '1%'         = 'SMC_0402R'          | '(SMC_0402R_C)'                        | 'RESISTOR, SINGLE,16.2OHM,THICK FILM,1%,50V,.063W,-55/125C,SMD,0402'                    | 'NFND'    
 'G155-016R2-01' | '16.2OHM'    | '1%'         = 'SMC_0402R'          | '(SMC_0402R_C)'                        | 'RESISTOR, SINGLE,16.2OHM,THICK FILM,1%,50V,.063W,-55/125C,SMD,0402'                    | ''        
 'CL100788A'     | '23.7OHM'    | '1%'         = 'SMC_0402R'          | '(SMC_0402R_C)'                        | 'RESISTOR, SINGLE,23.7OHM,THICK FILM,1%,50V,.063W,-55/125C,SMD,0402'                    | 'NFND'    
 'CL100789A'     | '2.49KOHM'   | '1%'         = 'SMC_0402R'          | '(SMC_0402R_C)'                        | 'RESISTOR, SINGLE,2.49KOHM,THICK FILM,1%,50V,.063W,-55/125C,SMD,0402'                   | 'NFND'    
 'CL100790A'     | '249KOHM'    | '1%'         = 'SMC_0402R'          | '(SMC_0402R_C)'                        | 'RESISTOR, SINGLE,249KOHM,THICK FILM,1%,50V,.063W,-55/125C,SMD,0402'                    | 'NFND'    
 'CL100791A'     | '56.2OHM'    | '1%'         = 'SMC_0402R'          | '(SMC_0402R_C)'                        | 'RESISTOR, SINGLE,56.2OHM,THICK FILM,1%,50V,.063W,-55/125C,SMD,0402'                    | 'NFND'    
 'CL100792A'     | '82.5OHM'    | '1%'         = 'SMC_0402R'          | '(SMC_0402R_C)'                        | 'RESISTOR, SINGLE,82.5OHM,THICK FILM,1%,50V,.063W,-55/125C,SMD,0402'                    | 'NFND'    
 'G152-00047-01' | '82.5OHM'    | '1%'         = 'SMC_0402R'          | '(SMC_0402R_C)'                        | 'RESISTOR, SINGLE,82.5OHM,THICK FILM,1%,50V,.063W,-55/125C,SMD,0402'                    | ''        
 'CL100793A'     | '909KOHM'    | '1%'         = 'SMC_0402R'          | '(SMC_0402R_C)'                        | 'RESISTOR, SINGLE,909KOHM,THICK FILM,1%,50V,.063W,-55/125C,SMD,0402'                    | 'NFND'    
 'CL100794A'     | '1OHM'       | '1%'         = 'SMC_0603R'          | '(SMC_0603R)'                          | 'RESISTOR, SINGLE,1OHM,THICK FILM,1%,50V,.1W,-55/125C,SMD,0603'                         | 'NFND'    
 'G152-00016-01' | '1OHM'       | '1%'         = 'SMC_0603R'          | '(SMC_0603R)'                          | 'RESISTOR, SINGLE,1OHM,THICK FILM,1%,50V,.1W,-55/125C,SMD,0603'                         | ''        
 'CL100795A'     | '100OHM'     | '1%'         = 'SMC_0603R'          | '(SMC_0603R)'                          | 'RESISTOR, SINGLE,100OHM,THICK FILM,1%,50V,.1W,-55/125C,0603'                           | 'NFND'    
 'CL100796A'     | '1KOHM'      | '1%'         = 'SMC_0603R'          | '(SMC_0603R)'                          | 'RESISTOR, SINGLE,1KOHM,THICK FILM,1%,50V,.1W,-55/125C,0603'                            | 'NFND'    
 'G152-00028-01' | '1KOHM'      | '1%'         = 'SMC_0603R'          | '(SMC_0603R)'                          | 'RESISTOR, SINGLE,1KOHM,THICK FILM,1%,50V,.1W,-55/125C,0603'                            | ''        
 'CL100797A'     | '10KOHM'     | '1%'         = 'SMC_0603R'          | '(SMC_0603R)'                          | 'RESISTOR, SINGLE,10KOHM,THICK FILM,1%,50V,.1W,-55/125C,0603'                           | 'NFND'    
 'G152-00048-01' | '10KOHM'     | '1%'         = 'SMC_0603R'          | '(SMC_0603R)'                          | 'RESISTOR, SINGLE,10KOHM,THICK FILM,1%,50V,.1W,-55/125C,0603'                           | ''        
 'CL100798A'     | '100KOHM'    | '1%'         = 'SMC_0603R'          | '(SMC_0603R)'                          | 'RESISTOR, SINGLE,100KOHM,THICK FILM,1%,50V,.1W,-55/125C,0603'                          | 'NFND'    
 'G152-00027-01' | '100KOHM'    | '1%'         = 'SMC_0603R'          | '(SMC_0603R)'                          | 'RESISTOR, SINGLE,100KOHM,THICK FILM,1%,50V,.1W,-55/125C,0603'                          | ''        
 'CL100799A'     | '1MOHM'      | '1%'         = 'SMC_0603R'          | '(SMC_0603R)'                          | 'RESISTOR, SINGLE,1MOHM,THICK FILM,1%,50V,.1W,-55/125C,0603'                            | 'NFND'    
 'CL100800A'     | '1.05KOHM'   | '1%'         = 'SMC_0603R'          | '(SMC_0603R)'                          | 'RESISTOR, SINGLE,1.05KOHM,THICK FILM,1%,50V,.1W,-55/125C,0603'                         | 'NFND'    
 'CL100801A'     | '10OHM'      | '1%'         = 'SMC_0603R'          | '(SMC_0603R)'                          | 'RESISTOR, SINGLE,10OHM,THICK FILM,1%,0V,.1W,-55/125C,0603'                             | 'NFND'    
 'G152-00049-01' | '10OHM'      | '1%'         = 'SMC_0603R'          | '(SMC_0603R)'                          | 'RESISTOR, SINGLE,10OHM,THICK FILM,1%,0V,.1W,-55/125C,0603'                             | ''        
 'CL100802A'     | '1.1KOHM'    | '1%'         = 'SMC_0603R'          | '(SMC_0603R)'                          | 'RESISTOR, SINGLE,1.1KOHM,THICK FILM,1%,50V,.1W,-55/125C,0603'                          | 'NFND'    
 'G152-00020-01' | '1.1KOHM'    | '1%'         = 'SMC_0603R'          | '(SMC_0603R)'                          | 'RESISTOR, SINGLE,1.1KOHM,THICK FILM,1%,50V,.1W,-55/125C,0603'                          | ''        
 'CL100803A'     | '11KOHM'     | '1%'         = 'SMC_0603R'          | '(SMC_0603R)'                          | 'RESISTOR, SINGLE,11KOHM,THICK FILM,1%,50V,.1W,-55/125C,0603'                           | 'NFND'    
 'CL100804A'     | '110KOHM'    | '1%'         = 'SMC_0603R'          | '(SMC_0603R)'                          | 'RESISTOR, SINGLE,110KOHM,THICK FILM,1%,50V,.1W,-55/125C,0603'                          | 'NFND'    
 'CL100805A'     | '11.5KOHM'   | '1%'         = 'SMC_0603R'          | '(SMC_0603R)'                          | 'RESISTOR, SINGLE,11.5KOHM,THICK FILM,1%,50V,.1W,-55/125C,0603'                         | 'NFND'    
 'CL100806A'     | '121OHM'     | '1%'         = 'SMC_0603R'          | '(SMC_0603R)'                          | 'RESISTOR, SINGLE,121OHM,THICK FILM,1%,50V,.1W,-55/125C,0603'                           | 'NFND'    
 'CL100807A'     | '1.21KOHM'   | '1%'         = 'SMC_0603R'          | '(SMC_0603R)'                          | 'RESISTOR, SINGLE,1.21KOHM,THICK FILM,1%,50V,.1W,-55/125C,0603'                         | 'NFND'    
 'CL100808A'     | '12.1KOHM'   | '1%'         = 'SMC_0603R'          | '(SMC_0603R)'                          | 'RESISTOR, SINGLE,12.1KOHM,THICK FILM,1%,50V,.1W,-55/125C,0603'                         | 'NFND'    
 'CL100809A'     | '121KOHM'    | '1%'         = 'SMC_0603R'          | '(SMC_0603R)'                          | 'RESISTOR, SINGLE,121KOHM,THICK FILM,1%,50V,.1W,-55/125C,0603'                          | 'NFND'    
 'CL100810A'     | '12.1OHM'    | '1%'         = 'SMC_0603R'          | '(SMC_0603R)'                          | 'RESISTOR, SINGLE,12.1OHM,THICK FILM,1%,50V,.1W,-55/125C,0603'                          | 'NFND'    
 'CL100811A'     | '133OHM'     | '1%'         = 'SMC_0603R'          | '(SMC_0603R)'                          | 'RESISTOR, SINGLE,133OHM,THICK FILM,1%,50V,.1W,-55/125C,0603'                           | 'NFND'    
 'CL100812A'     | '1.33KOHM'   | '1%'         = 'SMC_0603R'          | '(SMC_0603R)'                          | 'RESISTOR, SINGLE,1.33KOHM,THICK FILM,1%,50V,.1W,-55/125C,0603'                         | 'NFND'    
 'CL100813A'     | '13.3KOHM'   | '1%'         = 'SMC_0603R'          | '(SMC_0603R)'                          | 'RESISTOR, SINGLE,13.3KOHM,THICK FILM,1%,50V,.1W,-55/125C,0603'                         | 'NFND'    
 'G156-01332-01' | '13.3KOHM'   | '1%'         = 'SMC_0603R'          | '(SMC_0603R)'                          | 'RESISTOR, SINGLE,13.3KOHM,THICK FILM,1%,50V,.1W,-55/125C,0603'                         | ''        
 'CL100814A'     | '147OHM'     | '1%'         = 'SMC_0603R'          | '(SMC_0603R)'                          | 'RESISTOR, SINGLE,147OHM,THICK FILM,1%,50V,.1W,-55/125C,0603'                           | 'NFND'    
 'CL100815A'     | '1.47KOHM'   | '1%'         = 'SMC_0603R'          | '(SMC_0603R)'                          | 'RESISTOR, SINGLE,1.47KOHM,THICK FILM,1%,50V,.1W,-55/125C,0603'                         | 'NFND'    
 'CL100816A'     | '14.7KOHM'   | '1%'         = 'SMC_0603R'          | '(SMC_0603R)'                          | 'RESISTOR, SINGLE,14.7KOHM,THICK FILM,1%,50V,.1W,-55/125C,0603'                         | 'NFND'    
 'CL100817A'     | '147KOHM'    | '1%'         = 'SMC_0603R'          | '(SMC_0603R)'                          | 'RESISTOR, SINGLE,147KOHM,THICK FILM,1%,50V,.1W,-55/125C,0603'                          | 'NFND'    
 'CL100818A'     | '14.7OHM'    | '1%'         = 'SMC_0603R'          | '(SMC_0603R)'                          | 'RESISTOR, SINGLE,14.7OHM,THICK FILM,1%,50V,.1W,-55/125C,0603'                          | 'NFND'    
 'CL100819A'     | '150OHM'     | '1%'         = 'SMC_0603R'          | '(SMC_0603R)'                          | 'RESISTOR, SINGLE,150OHM,THICK FILM,1%,50V,.1W,-55/125C,0603'                           | 'NFND'    
 'CL100820A'     | '1.5KOHM'    | '1%'         = 'SMC_0603R'          | '(SMC_0603R)'                          | 'RESISTOR, SINGLE,1.5KOHM,THICK FILM,1%,9V,.1W,-55/125C,0603'                           | 'NFND'    
 'CL100821A'     | '15.4KOHM'   | '1%'         = 'SMC_0603R'          | '(SMC_0603R)'                          | 'RESISTOR, SINGLE,15.4KOHM,THICK FILM,1%,50V,.1W,-55/125C,0603'                         | 'NFND'    
 'CL100822A'     | '162OHM'     | '1%'         = 'SMC_0603R'          | '(SMC_0603R)'                          | 'RESISTOR, SINGLE,162OHM,THICK FILM,1%,50V,.1W,-55/125C,0603'                           | 'NFND'    
 'CL100823A'     | '1.62KOHM'   | '1%'         = 'SMC_0603R'          | '(SMC_0603R)'                          | 'RESISTOR, SINGLE,1.62KOHM,THICK FILM,1%,50V,.1W,-55/125C,0603'                         | 'NFND'    
 'CL100824A'     | '16.2KOHM'   | '1%'         = 'SMC_0603R'          | '(SMC_0603R)'                          | 'RESISTOR, SINGLE,16.2KOHM,THICK FILM,1%,50V,.1W,-55/125C,0603'                         | 'NFND'    
 'CL100825A'     | '169OHM'     | '1%'         = 'SMC_0603R'          | '(SMC_0603R)'                          | 'RESISTOR, SINGLE,169OHM,THICK FILM,1%,50V,.1W,-55/125C,0603'                           | 'NFND'    
 'CL100826A'     | '16.2OHM'    | '1%'         = 'SMC_0603R'          | '(SMC_0603R)'                          | 'RESISTOR, SINGLE,16.2OHM,THICK FILM,1%,50V,.1W,-55/125C,0603'                          | 'NFND'    
 'CL100827A'     | '178OHM'     | '1%'         = 'SMC_0603R'          | '(SMC_0603R)'                          | 'RESISTOR, SINGLE,178OHM,THICK FILM,1%,50V,.1W,-55/125C,0603'                           | 'NFND'    
 'CL100828A'     | '1.78KOHM'   | '1%'         = 'SMC_0603R'          | '(SMC_0603R)'                          | 'RESISTOR, SINGLE,1.78KOHM,THICK FILM,1%,50V,.1W,-55/125C,0603'                         | 'NFND'    
 'CL100829A'     | '17.8KOHM'   | '1%'         = 'SMC_0603R'          | '(SMC_0603R)'                          | 'RESISTOR, SINGLE,17.8KOHM,THICK FILM,1%,50V,.1W,-55/125C,0603'                         | 'NFND'    
 'CL100830A'     | '178KOHM'    | '1%'         = 'SMC_0603R'          | '(SMC_0603R)'                          | 'RESISTOR, SINGLE,178KOHM,THICK FILM,1%,50V,.1W,-55/125C,0603'                          | 'NFND'    
 'CL100831A'     | '1.87KOHM'   | '1%'         = 'SMC_0603R'          | '(SMC_0603R)'                          | 'RESISTOR, SINGLE,1.87KOHM,THICK FILM,1%,50V,.1W,-55/125C,0603'                         | 'NFND'    
 'CL100832A'     | '196OHM'     | '1%'         = 'SMC_0603R'          | '(SMC_0603R)'                          | 'RESISTOR, SINGLE,196OHM,THICK FILM,1%,50V,.1W,-55/125C,0603'                           | 'NFND'    
 'CL100833A'     | '1.96KOHM'   | '1%'         = 'SMC_0603R'          | '(SMC_0603R)'                          | 'RESISTOR, SINGLE,1.96KOHM,THICK FILM,1%,50V,.1W,-55/125C,0603'                         | 'NFND'    
 'CL100834A'     | '19.6KOHM'   | '1%'         = 'SMC_0603R'          | '(SMC_0603R)'                          | 'RESISTOR, SINGLE,19.6KOHM,THICK FILM,1%,50V,.1W,-55/125C,0603'                         | 'NFND'    
 'CL100835A'     | '19.6OHM'    | '1%'         = 'SMC_0603R'          | '(SMC_0603R)'                          | 'RESISTOR, SINGLE,19.6OHM,THICK FILM,1%,50V,.1W,-55/125C,0603'                          | 'NFND'    
 'CL100836A'     | '20.5KOHM'   | '1%'         = 'SMC_0603R'          | '(SMC_0603R)'                          | 'RESISTOR, SINGLE,20.5KOHM,THICK FILM,1%,50V,.1W,-55/125C,0603'                         | 'NFND'    
 'CL100837A'     | '215OHM'     | '1%'         = 'SMC_0603R'          | '(SMC_0603R)'                          | 'RESISTOR, SINGLE,215OHM,THICK FILM,1%,50V,.1W,-55/125C,0603'                           | 'NFND'    
 'CL100838A'     | '21.5KOHM'   | '1%'         = 'SMC_0603R'          | '(SMC_0603R)'                          | 'RESISTOR, SINGLE,21.5KOHM,THICK FILM,1%,50V,.1W,-55/125C,0603'                         | 'NFND'    
 'G156-02152-01' | '21.5KOHM'   | '1%'         = 'SMC_0603R'          | '(SMC_0603R)'                          | 'RESISTOR, SINGLE,21.5KOHM,THICK FILM,1%,50V,.1W,-55/125C,0603'                         | ''        
 'CL100839A'     | '215KOHM'    | '1%'         = 'SMC_0603R'          | '(SMC_0603R)'                          | 'RESISTOR, SINGLE,215KOHM,THICK FILM,1%,50V,.1W,-55/125C,0603'                          | 'NFND'    
 'CL100840A'     | '21.5OHM'    | '1%'         = 'SMC_0603R'          | '(SMC_0603R)'                          | 'RESISTOR, SINGLE,21.5OHM,THICK FILM,1%,50V,.1W,-55/125C,0603'                          | 'NFND'    
 'CL100841A'     | '226KOHM'    | '1%'         = 'SMC_0603R'          | '(SMC_0603R)'                          | 'RESISTOR, SINGLE,226KOHM,THICK FILM,1%,50V,.063W,-55/125C,0603'                        | 'NFND'    
 'CL100842A'     | '237OHM'     | '1%'         = 'SMC_0603R'          | '(SMC_0603R)'                          | 'RESISTOR, SINGLE,237OHM,THICK FILM,1%,50V,.1W,-55/125C,0603'                           | 'NFND'    
 'CL100843A'     | '2.37KOHM'   | '1%'         = 'SMC_0603R'          | '(SMC_0603R)'                          | 'RESISTOR, SINGLE,2.37KOHM,THICK FILM,1%,50V,.1W,-55/125C,0603'                         | 'NFND'    
 'CL100844A'     | '237KOHM'    | '1%'         = 'SMC_0603R'          | '(SMC_0603R)'                          | 'RESISTOR, SINGLE,237KOHM,THICK FILM,1%,50V,.1W,-55/125C,0603'                          | 'NFND'    
 'CL100845A'     | '23.7OHM'    | '1%'         = 'SMC_0603R'          | '(SMC_0603R)'                          | 'RESISTOR, SINGLE,23.7OHM,THICK FILM,1%,50V,.1W,-55/125C,0603'                          | 'NFND'    
 'CL100846A'     | '249KOHM'    | '1%'         = 'SMC_0603R'          | '(SMC_0603R)'                          | 'RESISTOR, SINGLE,249KOHM,THICK FILM,1%,50V,.1W,-55/125C,0603'                          | 'NFND'    
 'CL100847A'     | '261OHM'     | '1%'         = 'SMC_0603R'          | '(SMC_0603R)'                          | 'RESISTOR, SINGLE,261OHM,THICK FILM,1%,50V,.1W,-55/125C,0603'                           | 'NFND'    
 'CL100848A'     | '2.61KOHM'   | '1%'         = 'SMC_0603R'          | '(SMC_0603R)'                          | 'RESISTOR, SINGLE,2.61KOHM,THICK FILM,1%,12V,.1W,-55/125C,0603'                         | 'NFND'    
 'CL100849A'     | '26.1KOHM'   | '1%'         = 'SMC_0603R'          | '(SMC_0603R)'                          | 'RESISTOR, SINGLE,26.1KOHM,THICK FILM,1%,50V,.1W,-55/125C,0603'                         | ''        
 'G152-00022-01' | '26.1KOHM'   | '1%'         = 'SMC_0603R'          | '(SMC_0603R)'                          | 'RESISTOR, SINGLE,26.1KOHM,THICK FILM,1%,50V,.1W,-55/125C,0603'                         | ''        
 'CL100850A'     | '261KOHM'    | '1%'         = 'SMC_0603R'          | '(SMC_0603R)'                          | 'RESISTOR, SINGLE,261KOHM,THICK FILM,1%,50V,.1W,-55/125C,0603'                          | 'NFND'    
 'CL100851A'     | '26.1OHM'    | '1%'         = 'SMC_0603R'          | '(SMC_0603R)'                          | 'RESISTOR, SINGLE,26.1OHM,THICK FILM,1%,1V,.1W,-55/125C,0603'                           | 'NFND'    
 'CL100852A'     | '27.4KOHM'   | '1%'         = 'SMC_0603R'          | '(SMC_0603R)'                          | 'RESISTOR, SINGLE,27.4KOHM,THICK FILM,1%,50V,.1W,-55/125C,0603'                         | 'NFND'    
 'CL100853A'     | '287OHM'     | '1%'         = 'SMC_0603R'          | '(SMC_0603R)'                          | 'RESISTOR, SINGLE,287OHM,THICK FILM,1%,50V,.1W,-55/125C,0603'                           | 'NFND'    
 'CL100854A'     | '2.87KOHM'   | '1%'         = 'SMC_0603R'          | '(SMC_0603R)'                          | 'RESISTOR, SINGLE,2.87KOHM,THICK FILM,1%,50V,.1W,-55/125C,0603'                         | 'NFND'    
 'CL100855A'     | '28.7KOHM'   | '1%'         = 'SMC_0603R'          | '(SMC_0603R)'                          | 'RESISTOR, SINGLE,28.7KOHM,THICK FILM,1%,50V,.1W,-55/125C,0603'                         | 'NFND'    
 'CL100856A'     | '301OHM'     | '1%'         = 'SMC_0603R'          | '(SMC_0603R)'                          | 'RESISTOR, SINGLE,301OHM,THICK FILM,1%,50V,.1W,-55/125C,0603'                           | 'NFND'    
 'CL100857A'     | '3.01KOHM'   | '1%'         = 'SMC_0603R'          | '(SMC_0603R)'                          | 'RESISTOR, SINGLE,3.01KOHM,THICK FILM,1%,50V,.1W,-55/125C,0603'                         | 'NFND'    
 'CL100858A'     | '30.1KOHM'   | '1%'         = 'SMC_0603R'          | '(SMC_0603R)'                          | 'RESISTOR, SINGLE,30.1KOHM,THICK FILM,1%,50V,.1W,-55/125C,0603'                         | 'NFND'    
 'CL100859A'     | '309OHM'     | '1%'         = 'SMC_0603R'          | '(SMC_0603R)'                          | 'RESISTOR, SINGLE,309OHM,THICK FILM,1%,50V,.1W,-55/125C,0603'                           | 'NFND'    
 'CL100860A'     | '316OHM'     | '1%'         = 'SMC_0603R'          | '(SMC_0603R)'                          | 'RESISTOR, SINGLE,316OHM,THICK FILM,1%,50V,.1W,-55/125C,0603'                           | 'NFND'    
 'CL100861A'     | '3.16KOHM'   | '1%'         = 'SMC_0603R'          | '(SMC_0603R)'                          | 'RESISTOR, SINGLE,3.16KOHM,THICK FILM,1%,50V,.1W,-55/125C,0603'                         | 'NFND'    
 'CL100862A'     | '31.6KOHM'   | '1%'         = 'SMC_0603R'          | '(SMC_0603R)'                          | 'RESISTOR, SINGLE,31.6KOHM,THICK FILM,1%,50V,.1W,-55/125C,0603'                         | 'NFND'    
 'CL100863A'     | '316KOHM'    | '1%'         = 'SMC_0603R'          | '(SMC_0603R)'                          | 'RESISTOR, SINGLE,316KOHM,THICK FILM,1%,50V,.1W,-55/125C,0603'                          | 'NFND'    
 'CL100864A'     | '31.6OHM'    | '1%'         = 'SMC_0603R'          | '(SMC_0603R)'                          | 'RESISTOR, SINGLE,31.6OHM,THICK FILM,1%,50V,.1W,-55/125C,0603'                          | 'NFND'    
 'CL100865A'     | '332OHM'     | '1%'         = 'SMC_0603R'          | '(SMC_0603R)'                          | 'RESISTOR, SINGLE,332OHM,THICK FILM,1%,50V,.1W,-55/125C,0603'                           | 'NFND'    
 'CL100866A'     | '33.2KOHM'   | '1%'         = 'SMC_0603R'          | '(SMC_0603R)'                          | 'RESISTOR, SINGLE,33.2KOHM,THICK FILM,1%,50V,.1W,-55/125C,0603'                         | 'NFND'    
 'CL100867A'     | '348OHM'     | '1%'         = 'SMC_0603R'          | '(SMC_0603R)'                          | 'RESISTOR, SINGLE,348OHM,THICK FILM,1%,50V,.1W,-55/125C,0603'                           | 'NFND'    
 'CL100868A'     | '3.48KOHM'   | '1%'         = 'SMC_0603R'          | '(SMC_0603R)'                          | 'RESISTOR, SINGLE,3.48KOHM,THICK FILM,1%,50V,.1W,-55/125C,0603'                         | 'NFND'    
 'CL100869A'     | '34.8KOHM'   | '1%'         = 'SMC_0603R'          | '(SMC_0603R)'                          | 'RESISTOR, SINGLE,34.8KOHM,THICK FILM,1%,50V,.1W,-55/125C,0603'                         | 'NFND'    
 'CL100870A'     | '348KOHM'    | '1%'         = 'SMC_0603R'          | '(SMC_0603R)'                          | 'RESISTOR, SINGLE,348KOHM,THICK FILM,1%,50V,.1W,-55/125C,0603'                          | 'NFND'    
 'CL100871A'     | '34.8OHM'    | '1%'         = 'SMC_0603R'          | '(SMC_0603R)'                          | 'RESISTOR, SINGLE,34.8OHM,THICK FILM,1%,50V,.1W,-55/125C,0603'                          | 'NFND'    
 'CL100872A'     | '3.65KOHM'   | '1%'         = 'SMC_0603R'          | '(SMC_0603R)'                          | 'RESISTOR, SINGLE,3.65KOHM,THICK FILM,1%,50V,.1W,-55/125C,0603'                         | 'NFND'    
 'CL100873A'     | '383OHM'     | '1%'         = 'SMC_0603R'          | '(SMC_0603R)'                          | 'RESISTOR, SINGLE,383OHM,THICK FILM,1%,50V,.1W,-55/125C,0603'                           | 'NFND'    
 'CL100874A'     | '3.83KOHM'   | '1%'         = 'SMC_0603R'          | '(SMC_0603R)'                          | 'RESISTOR, SINGLE,3.83KOHM,THICK FILM,1%,50V,.1W,-55/125C,0603'                         | 'NFND'    
 'CL100875A'     | '38.3KOHM'   | '1%'         = 'SMC_0603R'          | '(SMC_0603R)'                          | 'RESISTOR, SINGLE,38.3KOHM,THICK FILM,1%,50V,.1W,-55/125C,0603'                         | 'NFND'    
 'CL100876A'     | '383KOHM'    | '1%'         = 'SMC_0603R'          | '(SMC_0603R)'                          | 'RESISTOR, SINGLE,383KOHM,THICK FILM,1%,50V,.1W,-55/125C,0603'                          | 'NFND'    
 'CL100877A'     | '38.3OHM'    | '1%'         = 'SMC_0603R'          | '(SMC_0603R)'                          | 'RESISTOR, SINGLE,38.3OHM,THICK FILM,1%,50V,.1W,-55/125C,0603'                          | 'NFND'    
 'CL100878A'     | '40.2KOHM'   | '1%'         = 'SMC_0603R'          | '(SMC_0603R)'                          | 'RESISTOR, SINGLE,40.2KOHM,THICK FILM,1%,50V,.1W,-55/125C,0603'                         | 'NFND'    
 'G152-00026-01' | '40.2KOHM'   | '1%'         = 'SMC_0603R'          | '(SMC_0603R)'                          | 'RESISTOR, SINGLE,40.2KOHM,THICK FILM,1%,50V,.1W,-55/125C,0603'                         | ''        
 'CL100879A'     | '40.2OHM'    | '1%'         = 'SMC_0603R'          | '(SMC_0603R)'                          | 'RESISTOR, SINGLE,40.2OHM,THICK FILM,1%,50V,.1W,-55/125C,0603'                          | 'NFND'    
 'CL100880A'     | '422OHM'     | '1%'         = 'SMC_0603R'          | '(SMC_0603R)'                          | 'RESISTOR, SINGLE,422OHM,THICK FILM,1%,50V,.1W,-55/125C,0603'                           | 'NFND'    
 'CL100881A'     | '4.22KOHM'   | '1%'         = 'SMC_0603R'          | '(SMC_0603R)'                          | 'RESISTOR, SINGLE,4.22KOHM,THICK FILM,1%,50V,.1W,-55/125C,0603'                         | 'NFND'    
 'CL100882A'     | '42.2KOHM'   | '1%'         = 'SMC_0603R'          | '(SMC_0603R)'                          | 'RESISTOR, SINGLE,42.2KOHM,THICK FILM,1%,50V,.1W,-55/125C,0603'                         | 'NFND'    
 'CL100883A'     | '42.2OHM'    | '1%'         = 'SMC_0603R'          | '(SMC_0603R)'                          | 'RESISTOR, SINGLE,42.2OHM,THICK FILM,1%,50V,.1W,-55/125C,0603'                          | 'NFND'    
 'CL100884A'     | '464OHM'     | '1%'         = 'SMC_0603R'          | '(SMC_0603R)'                          | 'RESISTOR, SINGLE,464OHM,THICK FILM,1%,50V,.1W,-55/125C,0603'                           | 'NFND'    
 'CL100885A'     | '4.64KOHM'   | '1%'         = 'SMC_0603R'          | '(SMC_0603R)'                          | 'RESISTOR, SINGLE,4.64KOHM,THICK FILM,1%,50V,.1W,-55/125C,0603'                         | 'NFND'    
 'CL100886A'     | '464KOHM'    | '1%'         = 'SMC_0603R'          | '(SMC_0603R)'                          | 'RESISTOR, SINGLE,464KOHM,THICK FILM,1%,50V,.1W,-55/125C,0603'                          | 'NFND'    
 'CL100887A'     | '46.4OHM'    | '1%'         = 'SMC_0603R'          | '(SMC_0603R)'                          | 'RESISTOR, SINGLE,46.4OHM,THICK FILM,1%,50V,.1W,-55/125C,0603'                          | 'NFND'    
 'CL100888A'     | '4.7KOHM'    | '1%'         = 'SMC_0603R'          | '(SMC_0603R)'                          | 'RESISTOR, SINGLE,4.7KOHM,THICK FILM,1%,50V,.1W,-55/125C,0603'                          | 'NFND'    
 'CL100889A'     | '499KOHM'    | '1%'         = 'SMC_0603R'          | '(SMC_0603R)'                          | 'RESISTOR, SINGLE,499KOHM,THICK FILM,1%,50V,.1W,-55/125C,0603'                          | 'NFND'    
 'CL100890A'     | '49.9OHM'    | '1%'         = 'SMC_0603R'          | '(SMC_0603R)'                          | 'RESISTOR, SINGLE,49.9OHM,THICK FILM,1%,50V,.1W,-55/125C,0603'                          | 'NFND'    
 'G152-00050-01' | '49.9OHM'    | '1%'         = 'SMC_0603R'          | '(SMC_0603R)'                          | 'RESISTOR, SINGLE,49.9OHM,THICK FILM,1%,50V,.1W,-55/125C,0603'                          | ''        
 'CL100891A'     | '511OHM'     | '1%'         = 'SMC_0603R'          | '(SMC_0603R)'                          | 'RESISTOR, SINGLE,511OHM,THICK FILM,1%,50V,.1W,-55/125C,0603'                           | 'NFND'    
 'CL100892A'     | '5.11KOHM'   | '1%'         = 'SMC_0603R'          | '(SMC_0603R)'                          | 'RESISTOR, SINGLE,5.11KOHM,THICK FILM,1%,50V,.1W,-55/125C,0603'                         | 'NFND'    
 'G156-05111-01' | '5.11KOHM'   | '1%'         = 'SMC_0603R'          | '(SMC_0603R)'                          | 'RESISTOR, SINGLE,5.11KOHM,THICK FILM,1%,50V,.1W,-55/125C,0603'                         | ''        
 'CL100893A'     | '51.1KOHM'   | '1%'         = 'SMC_0603R'          | '(SMC_0603R)'                          | 'RESISTOR, SINGLE,51.1KOHM,THICK FILM,1%,50V,.1W,-55/125C,0603'                         | 'NFND'    
 'CL100894A'     | '51.1OHM'    | '1%'         = 'SMC_0603R'          | '(SMC_0603R)'                          | 'RESISTOR, SINGLE,51.1OHM,THICK FILM,1%,50V,.1W,-55/125C,0603'                          | 'NFND'    
 'G156-051R1-01' | '51.1OHM'    | '1%'         = 'SMC_0603R'          | '(SMC_0603R)'                          | 'RESISTOR, SINGLE,51.1OHM,THICK FILM,1%,50V,.1W,-55/125C,0603'                          | ''        
 'CL100895A'     | '562OHM'     | '1%'         = 'SMC_0603R'          | '(SMC_0603R)'                          | 'RESISTOR, SINGLE,562OHM,THICK FILM,1%,50V,.1W,-55/125C,0603'                           | 'NFND'    
 'CL100896A'     | '5.62KOHM'   | '1%'         = 'SMC_0603R'          | '(SMC_0603R)'                          | 'RESISTOR, SINGLE,5.62KOHM,THICK FILM,1%,50V,.1W,-55/125C,0603'                         | 'NFND'    
 'G156-05621-01' | '5.62KOHM'   | '1%'         = 'SMC_0603R'          | '(SMC_0603R)'                          | 'RESISTOR, SINGLE,5.62KOHM,THICK FILM,1%,50V,.1W,-55/125C,0603'                         | ''        
 'CL100897A'     | '56.2KOHM'   | '1%'         = 'SMC_0603R'          | '(SMC_0603R)'                          | 'RESISTOR, SINGLE,56.2KOHM,THICK FILM,1%,50V,.1W,-55/125C,0603'                         | 'NFND'    
 'CL100898A'     | '56.2OHM'    | '1%'         = 'SMC_0603R'          | '(SMC_0603R)'                          | 'RESISTOR, SINGLE,56.2OHM,THICK FILM,1%,50V,.1W,-55/125C,0603'                          | 'NFND'    
 'CL100899A'     | '619OHM'     | '1%'         = 'SMC_0603R'          | '(SMC_0603R)'                          | 'RESISTOR, SINGLE,619OHM,THICK FILM,1%,50V,.1W,-55/125C,0603'                           | 'NFND'    
 'CL100900A'     | '6.19KOHM'   | '1%'         = 'SMC_0603R'          | '(SMC_0603R)'                          | 'RESISTOR, SINGLE,6.19KOHM,THICK FILM,1%,50V,.1W,-55/125C,0603'                         | 'NFND'    
 'CL100901A'     | '61.9KOHM'   | '1%'         = 'SMC_0603R'          | '(SMC_0603R)'                          | 'RESISTOR, SINGLE,61.9KOHM,THICK FILM,1%,50V,.1W,-55/125C,0603'                         | 'NFND'    
 'CL100902A'     | '619KOHM'    | '1%'         = 'SMC_0603R'          | '(SMC_0603R)'                          | 'RESISTOR, SINGLE,619KOHM,THICK FILM,1%,50V,.1W,-55/125C,0603'                          | 'NFND'    
 'CL100903A'     | '681OHM'     | '1%'         = 'SMC_0603R'          | '(SMC_0603R)'                          | 'RESISTOR, SINGLE,681OHM,THICK FILM,1%,50V,.1W,-55/125C,0603'                           | 'NFND'    
 'G152-00024-01' | '681OHM'     | '1%'         = 'SMC_0603R'          | '(SMC_0603R)'                          | 'RESISTOR, SINGLE,681OHM,THICK FILM,1%,50V,.1W,-55/125C,0603'                           | ''        
 'CL100904A'     | '6.81KOHM'   | '1%'         = 'SMC_0603R'          | '(SMC_0603R)'                          | 'RESISTOR, SINGLE,6.81KOHM,THICK FILM,1%,50V,.1W,-55/125C,0603'                         | 'NFND'    
 'CL100905A'     | '68.1KOHM'   | '1%'         = 'SMC_0603R'          | '(SMC_0603R)'                          | 'RESISTOR, SINGLE,68.1KOHM,THICK FILM,1%,50V,.1W,-55/125C,0603'                         | 'NFND'    
 'CL100906A'     | '681KOHM'    | '1%'         = 'SMC_0603R'          | '(SMC_0603R)'                          | 'RESISTOR, SINGLE,681KOHM,THICK FILM,1%,50V,.1W,-55/125C,0603'                          | 'NFND'    
 'CL100907A'     | '68.1OHM'    | '1%'         = 'SMC_0603R'          | '(SMC_0603R)'                          | 'RESISTOR, SINGLE,68.1OHM,THICK FILM,1%,50V,.1W,-55/125C,0603'                          | 'NFND'    
 'CL100908A'     | '750OHM'     | '1%'         = 'SMC_0603R'          | '(SMC_0603R)'                          | 'RESISTOR, SINGLE,750OHM,THICK FILM,1%,50V,.1W,-55/125C,0603'                           | 'NFND'    
 'CL100909A'     | '7.5KOHM'    | '1%'         = 'SMC_0603R'          | '(SMC_0603R)'                          | 'RESISTOR, SINGLE,7.5KOHM,THICK FILM,1%,50V,.1W,-55/125C,0603'                          | 'NFND'    
 'CL100910A'     | '75KOHM'     | '1%'         = 'SMC_0603R'          | '(SMC_0603R)'                          | 'RESISTOR, SINGLE,75KOHM,THICK FILM,1%,50V,.1W,-55/125C,0603'                           | 'NFND'    
 'CL100911A'     | '75OHM'      | '1%'         = 'SMC_0603R'          | '(SMC_0603R)'                          | 'RESISTOR, SINGLE,75OHM,THICK FILM,1%,50V,.1W,-55/125C,0603'                            | 'NFND'    
 'CL100912A'     | '78.7OHM'    | '1%'         = 'SMC_0603R'          | '(SMC_0603R)'                          | 'RESISTOR, SINGLE,78.7OHM,THICK FILM,1%,50V,.1W,-55/125C,0603'                          | 'NFND'    
 'CL100913A'     | '825OHM'     | '1%'         = 'SMC_0603R'          | '(SMC_0603R)'                          | 'RESISTOR, SINGLE,825OHM,THICK FILM,1%,50V,.1W,-55/125C,0603'                           | 'NFND'    
 'G152-00023-01' | '825OHM'     | '1%'         = 'SMC_0603R'          | '(SMC_0603R)'                          | 'RESISTOR, SINGLE,825OHM,THICK FILM,1%,50V,.1W,-55/125C,0603'                           | ''        
 'CL100914A'     | '8.25KOHM'   | '1%'         = 'SMC_0603R'          | '(SMC_0603R)'                          | 'RESISTOR, SINGLE,8.25KOHM,THICK FILM,1%,50V,.1W,-55/125C,0603'                         | 'NFND'    
 'CL100915A'     | '82.5KOHM'   | '1%'         = 'SMC_0603R'          | '(SMC_0603R)'                          | 'RESISTOR, SINGLE,82.5KOHM,THICK FILM,1%,50V,.1W,-55/125C,0603'                         | 'NFND'    
 'CL100916A'     | '82.5OHM'    | '1%'         = 'SMC_0603R'          | '(SMC_0603R)'                          | 'RESISTOR, SINGLE,82.5OHM,THICK FILM,1%,50V,.1W,-55/125C,0603'                          | 'NFND'    
 'CL100917A'     | '909OHM'     | '1%'         = 'SMC_0603R'          | '(SMC_0603R)'                          | 'RESISTOR, SINGLE,909OHM,THICK FILM,1%,50V,.1W,-55/125C,0603'                           | 'NFND'    
 'CL100918A'     | '9.09KOHM'   | '1%'         = 'SMC_0603R'          | '(SMC_0603R)'                          | 'RESISTOR, SINGLE,9.09KOHM,THICK FILM,1%,23V,.1W,-55/125C,0603'                         | 'NFND'    
 'CL100919A'     | '90.9KOHM'   | '1%'         = 'SMC_0603R'          | '(SMC_0603R)'                          | 'RESISTOR, SINGLE,90.9KOHM,THICK FILM,1%,50V,.1W,-55/125C,0603'                         | 'NFND'    
 'CL100920A'     | '909KOHM'    | '1%'         = 'SMC_0603R'          | '(SMC_0603R)'                          | 'RESISTOR, SINGLE,909KOHM,THICK FILM,1%,50V,.1W,-55/125C,0603'                          | 'NFND'    
 'CL100921A'     | '90.9OHM'    | '1%'         = 'SMC_0603R'          | '(SMC_0603R)'                          | 'RESISTOR, SINGLE,90.9OHM,THICK FILM,1%,50V,.1W,-55/125C,0603'                          | 'NFND'    
 'CL100922A'     | '9.31KOHM'   | '1%'         = 'SMC_0603R'          | '(SMC_0603R)'                          | 'RESISTOR, SINGLE,9.31KOHM,1%,50V,.1W,-55/125C,0603'                                    | 'NFND'    
 'CL100923A'     | '110OHM'     | '1%'         = 'SMC_0603R'          | '(SMC_0603R)'                          | 'RESISTOR, SINGLE,110OHM,THIN FILM,1%,50V,.1W,-55/125C,0603'                            | 'NFND'    
 'CL100924A'     | '2.15KOHM'   | '1%'         = 'SMC_0603R'          | '(SMC_0603R)'                          | 'RESISTOR, SINGLE,2.15KOHM,THICK FILM,1%,50V,.1W,-55/125C,0603'                         | 'NFND'    
 'CL100925A'     | '23.7KOHM'   | '1%'         = 'SMC_0603R'          | '(SMC_0603R)'                          | 'RESISTOR, SINGLE,23.7KOHM,THICK FILM,1%,50V,.1W,-55/125C,0603'                         | 'NFND'    
 'CL100926A'     | '249OHM'     | '1%'         = 'SMC_0603R'          | '(SMC_0603R)'                          | 'RESISTOR, SINGLE,249OHM,THICK FILM,1%,50V,.1W,-55/125C,0603'                           | 'NFND'    
 'CL100927A'     | '46.4KOHM'   | '1%'         = 'SMC_0603R'          | '(SMC_0603R)'                          | 'RESISTOR, SINGLE,46.4KOHM,THICK FILM,1%,50V,.1W,-55/125C,0603'                         | 'NFND'    
 'CL100928A'     | '511KOHM'    | '1%'         = 'SMC_0603R'          | '(SMC_0603R)'                          | 'RESISTOR, SINGLE,511KOHM,THICK FILM,1%,50V,.1W,-55/125C,0603'                          | 'NFND'    
 'G156-05113-01' | '511KOHM'    | '1%'         = 'SMC_0603R'          | '(SMC_0603R)'                          | 'RESISTOR, SINGLE,511KOHM,THICK FILM,1%,50V,.1W,-55/125C,0603'                          | ''        
 'CL100929A'     | '100OHM'     | '1%'         = 'SMC_0805R'          | '(SMC_0805R)'                          | 'RESISTOR, SINGLE,100OHM,THICK FILM,5%,150V.125W,-55/125C,0805'                         | 'NFND'    
 'CL100930A'     | '1KOHM'      | '1%'         = 'SMC_0805R'          | '(SMC_0805R)'                          | 'RESISTOR, SINGLE,1KOHM,THICK FILM,1%,150V.125W,-55/125C,0805'                          | 'NFND'    
 'CL100931A'     | '10KOHM'     | '1%'         = 'SMC_0805R'          | '(SMC_0805R)'                          | 'RESISTOR, SINGLE,10KOHM,THICK FILM,1%,150V.125W,-55/125C,0805'                         | 'NFND'    
 'CL100932A'     | '100KOHM'    | '1%'         = 'SMC_0805R'          | '(SMC_0805R)'                          | 'RESISTOR, SINGLE,100KOHM,THICK FILM,1%,150V.125W,-55/125C,0805'                        | 'NFND'    
 'CL100933A'     | '1MOHM'      | '1%'         = 'SMC_0805R'          | '(SMC_0805R)'                          | 'RESISTOR, SINGLE,1MOHM,THICK FILM,1%,150V.125W,-55/125C,0805'                          | 'NFND'    
 'CL100934A'     | '1.33KOHM'   | '1%'         = 'SMC_0805R'          | '(SMC_0805R)'                          | 'RESISTOR, SINGLE,1.33KOHM,THICK FILM,1%,150V.125W,-55/125C,0805'                       | 'NFND'    
 'CL100935A'     | '147OHM'     | '1%'         = 'SMC_0805R'          | '(SMC_0805R)'                          | 'RESISTOR, SINGLE,147OHM,THICK FILM,1%,150V.125W,-55/125C,0805'                         | 'NFND'    
 'CL100936A'     | '1.47KOHM'   | '1%'         = 'SMC_0805R'          | '(SMC_0805R)'                          | 'RESISTOR, SINGLE,1.47KOHM,THICK FILM,1%,150V.125W,-55/125C,0805'                       | 'NFND'    
 'CL100937A'     | '14.7KOHM'   | '1%'         = 'SMC_0805R'          | '(SMC_0805R)'                          | 'RESISTOR, SINGLE,14.7KOHM,THICK FILM,1%,150V.125W,-55/125C,0805'                       | 'NFND'    
 'CL100938A'     | '147KOHM'    | '1%'         = 'SMC_0805R'          | '(SMC_0805R)'                          | 'RESISTOR, SINGLE,147KOHM,THICK FILM,1%,150V.125W,-55/125C,0805'                        | 'NFND'    
 'CL100939A'     | '15.8KOHM'   | '1%'         = 'SMC_0805R'          | '(SMC_0805R)'                          | 'RESISTOR, SINGLE,15.8KOHM,THICK FILM,1%,150V.125W,-55/125C,0805'                       | 'NFND'    
 'CL100940A'     | '1.78KOHM'   | '1%'         = 'SMC_0805R'          | '(SMC_0805R)'                          | 'RESISTOR, SINGLE,1.78KOHM,THICK FILM,1%,150V.125W,-55/125C,0805'                       | 'NFND'    
 'CL100941A'     | '1OHM'       | '1%'         = 'SMC_0805R'          | '(SMC_0805R)'                          | 'RESISTOR, SINGLE,1OHM,THICK FILM,1%,150V.125W,-55/125C,0805'                           | 'NFND'    
 'CL100942A'     | '2.15KOHM'   | '1%'         = 'SMC_0805R'          | '(SMC_0805R)'                          | 'RESISTOR, SINGLE,2.15KOHM,THICK FILM,1%,150V.125W,-55/125C,0805'                       | 'NFND'    
 'CL100943A'     | '21.5KOHM'   | '1%'         = 'SMC_0805R'          | '(SMC_0805R)'                          | 'RESISTOR, SINGLE,21.5KOHM,THICK FILM,1%,150V.125W,-55/125C,0805'                       | 'NFND'    
 'CL100944A'     | '215KOHM'    | '1%'         = 'SMC_0805R'          | '(SMC_0805R)'                          | 'RESISTOR, SINGLE,215KOHM,THICK FILM,1%,150V.125W,-55/125C,0805'                        | 'NFND'    
 'CL100945A'     | '21.5OHM'    | '1%'         = 'SMC_0805R'          | '(SMC_0805R)'                          | 'RESISTOR, SINGLE,21.5OHM,THICK FILM,1%,150V.125W,-55/125C,0805'                        | 'NFND'    
 'CL100946A'     | '237OHM'     | '1%'         = 'SMC_0805R'          | '(SMC_0805R)'                          | 'RESISTOR, SINGLE,237OHM,THICK FILM,1%,150V.125W,-55/125C,0805'                         | 'NFND'    
 'CL100947A'     | '23.7KOHM'   | '1%'         = 'SMC_0805R'          | '(SMC_0805R)'                          | 'RESISTOR, SINGLE,23.7KOHM,THICK FILM,1%,150V,.125W,-55/125C,0805'                      | 'NFND'    
 'CL100948A'     | '2.49KOHM'   | '1%'         = 'SMC_0805R'          | '(SMC_0805R)'                          | 'RESISTOR, SINGLE,2.49KOHM,THICK FILM,1%,150V.125W,-55/125C,0805'                       | 'NFND'    
 'CL100949A'     | '2.55KOHM'   | '1%'         = 'SMC_0805R'          | '(SMC_0805R)'                          | 'RESISTOR, SINGLE,2.55KOHM,CERAMIC/METAL,1%,150V.125W,-55/125C,0805'                    | 'NFND'    
 'CL100950A'     | '2.61KOHM'   | '1%'         = 'SMC_0805R'          | '(SMC_0805R)'                          | 'RESISTOR, SINGLE,2.61KOHM,THICK FILM,1%,150V.125W,-55/125C,0805'                       | 'NFND'    
 'CL100951A'     | '2.74KOHM'   | '1%'         = 'SMC_0805R'          | '(SMC_0805R)'                          | 'RESISTOR, SINGLE,2.74KOHM,THICK FILM,1%,150V.125W,-55/125C,0805'                       | 'NFND'    
 'CL100952A'     | '27.4KOHM'   | '1%'         = 'SMC_0805R'          | '(SMC_0805R)'                          | 'RESISTOR, SINGLE,27.4KOHM,THICK FILM,1%,150V.125W,-55/125C,0805'                       | 'NFND'    
 'CL100953A'     | '287OHM'     | '1%'         = 'SMC_0805R'          | '(SMC_0805R)'                          | 'RESISTOR, SINGLE,287OHM,THICK FILM,1%,150V.125W,-55/125C,0805'                         | 'NFND'    
 'CL100954A'     | '3.01KOHM'   | '1%'         = 'SMC_0805R'          | '(SMC_0805R)'                          | 'RESISTOR, SINGLE,3.01KOHM,THICK FILM,1%,150V.125W,-55/125C,0805'                       | 'NFND'    
 'CL100955A'     | '316OHM'     | '1%'         = 'SMC_0805R'          | '(SMC_0805R)'                          | 'RESISTOR, SINGLE,316OHM,THICK FILM,1%,150V.125W,-55/125C,0805'                         | 'NFND'    
 'CL100956A'     | '316KOHM'    | '1%'         = 'SMC_0805R'          | '(SMC_0805R)'                          | 'RESISTOR, SINGLE,316KOHM,THICK FILM,1%,150V,.125W,-55/125C,0805'                       | 'NFND'    
 'CL100957A'     | '33.2KOHM'   | '1%'         = 'SMC_0805R'          | '(SMC_0805R)'                          | 'RESISTOR, SINGLE,33.2KOHM,THICK FILM,1%,150V.125W,-55/125C,0805'                       | 'NFND'    
 'CL100958A'     | '3.48KOHM'   | '1%'         = 'SMC_0805R'          | '(SMC_0805R)'                          | 'RESISTOR, SINGLE,3.48KOHM,THICK FILM,1%,150V.125W,-55/125C,0805'                       | 'NFND'    
 'CL100959A'     | '3.83KOHM'   | '1%'         = 'SMC_0805R'          | '(SMC_0805R)'                          | 'RESISTOR, SINGLE,3.83KOHM,THICK FILM,1%,150V.125W,-55/125C,0805'                       | 'NFND'    
 'CL100960A'     | '38.3KOHM'   | '1%'         = 'SMC_0805R'          | '(SMC_0805R)'                          | 'RESISTOR, SINGLE,38.3KOHM,THICK FILM,1%,150V.125W,-55/125C,0805'                       | 'NFND'    
 'CL100961A'     | '42.2KOHM'   | '1%'         = 'SMC_0805R'          | '(SMC_0805R)'                          | 'RESISTOR, SINGLE,42.2KOHM,THICK FILM,1%,150V.125W,-55/125C,0805'                       | 'NFND'    
 'CL100962A'     | '464OHM'     | '1%'         = 'SMC_0805R'          | '(SMC_0805R)'                          | 'RESISTOR, SINGLE,464OHM,THICK FILM,1%,150V.125W,-55/125C,0805'                         | 'NFND'    
 'CL100963A'     | '4.64KOHM'   | '1%'         = 'SMC_0805R'          | '(SMC_0805R)'                          | 'RESISTOR, SINGLE,4.64KOHM,THICK FILM,1%,150V.125W,-55/125C,0805'                       | 'NFND'    
 'CL100964A'     | '46.4KOHM'   | '1%'         = 'SMC_0805R'          | '(SMC_0805R)'                          | 'RESISTOR, SINGLE,46.4KOHM,THICK FILM,1%,150V.125W,-55/125C,0805'                       | 'NFND'    
 'CL100965A'     | '464KOHM'    | '1%'         = 'SMC_0805R'          | '(SMC_0805R)'                          | 'RESISTOR, SINGLE,464KOHM,THICK FILM,1%,150V.125W,-55/125C,0805'                        | 'NFND'    
 'CL100966A'     | '511OHM'     | '1%'         = 'SMC_0805R'          | '(SMC_0805R)'                          | 'RESISTOR, SINGLE,511OHM,THICK FILM,1%,150V.125W,-55/125C,0805'                         | 'NFND'    
 'CL100967A'     | '51.1KOHM'   | '1%'         = 'SMC_0805R'          | '(SMC_0805R)'                          | 'RESISTOR, SINGLE,51.1KOHM,THICK FILM,1%,150V.125W,-55/125C,0805'                       | 'NFND'    
 'CL100968A'     | '51.1OHM'    | '1%'         = 'SMC_0805R'          | '(SMC_0805R)'                          | 'RESISTOR, SINGLE,51.1OHM,THICK FILM,1%,150V.125W,-55/125C,0805'                        | 'NFND'    
 'CL100969A'     | '562OHM'     | '1%'         = 'SMC_0805R'          | '(SMC_0805R)'                          | 'RESISTOR, SINGLE,562OHM,THICK FILM,1%,150V.125W,-55/125C,0805'                         | 'NFND'    
 'CL100970A'     | '5.62KOHM'   | '1%'         = 'SMC_0805R'          | '(SMC_0805R)'                          | 'RESISTOR, SINGLE,5.62KOHM,THICK FILM,1%,150V.125W,-55/125C,0805'                       | 'NFND'    
 'CL100971A'     | '56.2KOHM'   | '1%'         = 'SMC_0805R'          | '(SMC_0805R)'                          | 'RESISTOR, SINGLE,56.2KOHM,THICK FILM,1%,150V.125W,-55/125C,0805'                       | 'NFND'    
 'CL100972A'     | '5.11OHM'    | '1%'         = 'SMC_0805R'          | '(SMC_0805R)'                          | 'RESISTOR, SINGLE,5.11OHM,THICK FILM,1%,150V.125W,-55/125C,0805'                        | 'NFND'    
 'CL100973A'     | '6.19KOHM'   | '1%'         = 'SMC_0805R'          | '(SMC_0805R)'                          | 'RESISTOR, SINGLE,6.19KOHM,THICK FILM,1%,150V.125W,-55/125C,0805'                       | 'NFND'    
 'CL100974A'     | '6.81KOHM'   | '1%'         = 'SMC_0805R'          | '(SMC_0805R)'                          | 'RESISTOR, SINGLE,6.81KOHM,THICK FILM,1%,150V.125W,-55/125C,0805'                       | 'NFND'    
 'CL100975A'     | '750OHM'     | '1%'         = 'SMC_0805R'          | '(SMC_0805R)'                          | 'RESISTOR, SINGLE,750OHM,THICK FILM,1%,150V.125W,-55/125C,0805'                         | 'NFND'    
 'CL100976A'     | '75OHM'      | '1%'         = 'SMC_0805R'          | '(SMC_0805R)'                          | 'RESISTOR, SINGLE,75OHM,THICK FILM,1%,150V.125W,-55/125C,0805'                          | 'NFND'    
 'CL100977A'     | '825OHM'     | '1%'         = 'SMC_0805R'          | '(SMC_0805R)'                          | 'RESISTOR, SINGLE,825OHM,THICK FILM,1%,150V.125W,-55/125C,0805'                         | 'NFND'    
 'CL100978A'     | '8.25KOHM'   | '1%'         = 'SMC_0805R'          | '(SMC_0805R)'                          | 'RESISTOR, SINGLE,8.25KOHM,THICK FILM,1%,150V.125W,-55/125C,0805'                       | 'NFND'    
 'CL100979A'     | '82.5KOHM'   | '1%'         = 'SMC_0805R'          | '(SMC_0805R)'                          | 'RESISTOR, SINGLE,82.5KOHM,THICK FILM,1%,150V.125W,-55/125C,0805'                       | 'NFND'    
 'CL100980A'     | '9.53KOHM'   | '1%'         = 'SMC_0805R'          | '(SMC_0805R)'                          | 'RESISTOR, SINGLE,9.53KOHM,THICK FILM,1%,150V.125W,-55/125C,0805'                       | 'NFND'    
 'CL100981A'     | '2.43KOHM'   | '1%'         = 'SMC_0805R'          | '(SMC_0805R)'                          | 'RESISTOR, SINGLE,2.43KOHM,THICK FILM,1%,150V.125W,-55/125C,0805'                       | 'NFND'    
 'CL100982A'     | '3.01OHM'    | '1%'         = 'SMC_0805R'          | '(SMC_0805R)'                          | 'RESISTOR, SINGLE,3.01OHM,THICK FILM,1%,150V.125W,-55/125C,0805'                        | 'NFND'    
 'CL100983A'     | '36.5OHM'    | '1%'         = 'SMC_0805R'          | '(SMC_0805R)'                          | 'RESISTOR, SINGLE,36.5OHM,THICK FILM,1%,150V.125W,-55/125C,SMD,0805'                    | 'NFND'    
 'CL100984A'     | '1KOHM'      | '1%'         = 'SMC_1206R'          | '(SMC_1206R)'                          | 'RESISTOR, SINGLE,1KOHM,THICK FILM,1%,200V,.25W,-55/125C,1206'                          | 'NFND'    
 'G158-01001-01' | '1KOHM'      | '1%'         = 'SMC_1206R'          | '(SMC_1206R)'                          | 'RESISTOR, SINGLE,1KOHM,THICK FILM,1%,200V,.25W,-55/155C,1206'                          | ''        
 'CL100985A'     | '10KOHM'     | '1%'         = 'SMC_1206R'          | '(SMC_1206R)'                          | 'RESISTOR, SINGLE,10KOHM,THICK FILM,1%,200V,.25,-55/125C,1206'                          | 'NFND'    
 'G152-00060-01' | '10KOHM'     | '1%'         = 'SMC_1206R'          | '(SMC_1206R)'                          | 'RESISTOR, SINGLE,10KOHM,THICK FILM,1%,200V,.25,-55/125C,1206'                          | 'OBSOLETE'
 'CL100986A'     | '100KOHM'    | '1%'         = 'SMC_1206R'          | '(SMC_1206R)'                          | 'RESISTOR, SINGLE,100KOHM,THICK FILM,1%,200V,.25,-55/125C,1206'                         | 'NFND'    
 'CL100987A'     | '1MOHM'      | '1%'         = 'SMC_1206R'          | '(SMC_1206R)'                          | 'RESISTOR, SINGLE,1MOHM,THICK FILM,1%,200V,.25,-55/125C,1206'                           | 'NFND'    
 'CL100988A'     | '10.5KOHM'   | '1%'         = 'SMC_1206R'          | '(SMC_1206R)'                          | 'RESISTOR, SINGLE,10.5KOHM,THICK FILM,1%,200V,.25,-55/125C,1206'                        | 'NFND'    
 'CL100989A'     | '10OHM'      | '1%'         = 'SMC_1206R'          | '(SMC_1206R)'                          | 'RESISTOR, SINGLE,10OHM,THICK FILM,1%,200V,.25,-55/125C,1206'                           | 'NFND'    
 'G152-00058-01' | '10OHM'      | '1%'         = 'SMC_1206R'          | '(SMC_1206R)'                          | 'RESISTOR, SINGLE,10OHM,THICK FILM,1%,200V,.25,-55/125C,1206'                           | ''        
 'CL100990A'     | '110OHM'     | '1%'         = 'SMC_1206R'          | '(SMC_1206R)'                          | 'RESISTOR, SINGLE,110OHM,THICK FILM,1%,200V,.25,-55/125C,1206'                          | 'NFND'    
 'CL100993A'     | '121OHM'     | '1%'         = 'SMC_1206R'          | '(SMC_1206R)'                          | 'RESISTOR, SINGLE,121OHM,THICK FILM,1%,3.8V,.25,-55/125C,1206'                          | 'NFND'    
 'CL100994A'     | '1.21KOHM'   | '1%'         = 'SMC_1206R'          | '(SMC_1206R)'                          | 'RESISTOR, SINGLE,1.21KOHM,THICK FILM,1%,200V,.25,-55/125C,1206'                        | 'NFND'    
 'CL100995A'     | '12.1KOHM'   | '1%'         = 'SMC_1206R'          | '(SMC_1206R)'                          | 'RESISTOR, SINGLE,12.1KOHM,THICK FILM,1%,200V,.25,-55/125C,1206'                        | 'NFND'    
 'CL100996A'     | '121KOHM'    | '1%'         = 'SMC_1206R'          | '(SMC_1206R)'                          | 'RESISTOR, SINGLE,121KOHM,THICK FILM,1%,200V,.25,-55/125C,1206'                         | 'NFND'    
 'CL100997A'     | '12.4KOHM'   | '1%'         = 'SMC_1206R'          | '(SMC_1206R)'                          | 'RESISTOR, SINGLE,12.4KOHM,THICK FILM,1%,200V,.25,-55/125C,1206'                        | 'NFND'    
 'CL100998A'     | '12.1OHM'    | '1%'         = 'SMC_1206R'          | '(SMC_1206R)'                          | 'RESISTOR, SINGLE,12.1OHM,THICK FILM,1%,200V,.25,-55/125C,1206'                         | 'NFND'    
 'CL100999A'     | '133OHM'     | '1%'         = 'SMC_1206R'          | '(SMC_1206R)'                          | 'RESISTOR, SINGLE,133OHM,THICK FILM,1%,200V,.25,-55/125C,1206'                          | 'NFND'    
 'CL1001000A'    | '13.3KOHM'   | '1%'         = 'SMC_1206R'          | '(SMC_1206R)'                          | 'RESISTOR, SINGLE,13.3KOHM,THICK FILM,1%,200V,.25,-55/125C,1206'                        | 'NFND'    
 'CL1001001A'    | '13.3OHM'    | '1%'         = 'SMC_1206R'          | '(SMC_1206R)'                          | 'RESISTOR, SINGLE,13.3OHM,THICK FILM,1%,200V,.25,-55/125C,1206'                         | 'NFND'    
 'CL1001002A'    | '1.47KOHM'   | '1%'         = 'SMC_1206R'          | '(SMC_1206R)'                          | 'RESISTOR, SINGLE,1.47KOHM,THICK FILM,1%,200V,.25,-55/125C,1206'                        | 'NFND'    
 'CL1001003A'    | '14.7KOHM'   | '1%'         = 'SMC_1206R'          | '(SMC_1206R)'                          | 'RESISTOR, SINGLE,14.7KOHM,THICK FILM,1%,200V,.25,-55/125C,1206'                        | 'NFND'    
 'CL1001004A'    | '147KOHM'    | '1%'         = 'SMC_1206R'          | '(SMC_1206R)'                          | 'RESISTOR, SINGLE,147KOHM,THICK FILM,1%,200V,.25,-55/125C,1206'                         | 'NFND'    
 'CL1001005A'    | '162OHM'     | '1%'         = 'SMC_1206R'          | '(SMC_1206R)'                          | 'RESISTOR, SINGLE,162OHM,THICK FILM,1%,200V,.25,-55/125C,1206'                          | 'NFND'    
 'CL1001006A'    | '1.62KOHM'   | '1%'         = 'SMC_1206R'          | '(SMC_1206R)'                          | 'RESISTOR, SINGLE,1.62KOHM,THICK FILM,1%,200V,.25,-55/125C,1206'                        | 'NFND'    
 'CL1001007A'    | '16.2KOHM'   | '1%'         = 'SMC_1206R'          | '(SMC_1206R)'                          | 'RESISTOR, SINGLE,16.2KOHM,THICK FILM,.5%,200V,.25,-55/125C,1206'                       | 'NFND'    
 'CL1001008A'    | '162KOHM'    | '1%'         = 'SMC_1206R'          | '(SMC_1206R)'                          | 'RESISTOR, SINGLE,162KOHM,THICK FILM,1%,200V,.25,-55/125C,1206'                         | 'NFND'    
 'CL1001009A'    | '16.2OHM'    | '1%'         = 'SMC_1206R'          | '(SMC_1206R)'                          | 'RESISTOR, SINGLE,16.2OHM,THICK FILM,1%,200V,.25,-55/125C,1206'                         | 'NFND'    
 'CL1001010A'    | '178OHM'     | '1%'         = 'SMC_1206R'          | '(SMC_1206R)'                          | 'RESISTOR, SINGLE,178OHM,THICK FILM,1%,200V,.25,-55/125C,1206'                          | 'NFND'    
 'CL1001011A'    | '1.78KOHM'   | '1%'         = 'SMC_1206R'          | '(SMC_1206R)'                          | 'RESISTOR, SINGLE,1.78KOHM,THICK FILM,1%,200V,.25,-55/125C,1206'                        | 'NFND'    
 'CL1001012A'    | '17.8KOHM'   | '1%'         = 'SMC_1206R'          | '(SMC_1206R)'                          | 'RESISTOR, SINGLE,17.8KOHM,THICK FILM,1%,200V,.25,-55/125C,1206'                        | 'NFND'    
 'CL1001013A'    | '178KOHM'    | '1%'         = 'SMC_1206R'          | '(SMC_1206R)'                          | 'RESISTOR, SINGLE,178KOHM,THICK FILM,1%,200V,.25,-55/125C,1206'                         | 'NFND'    
 'CL1001014A'    | '1.96KOHM'   | '1%'         = 'SMC_1206R'          | '(SMC_1206R)'                          | 'RESISTOR, SINGLE,1.96KOHM,THICK FILM,1%,200V,.25,-55/125C,1206'                        | 'NFND'    
 'CL1001015A'    | '19.6KOHM'   | '1%'         = 'SMC_1206R'          | '(SMC_1206R)'                          | 'RESISTOR, SINGLE,19.6KOHM,THICK FILM,1%,200V,.25,-55/125C,1206'                        | 'NFND'    
 'CL1001016A'    | '196KOHM'    | '1%'         = 'SMC_1206R'          | '(SMC_1206R)'                          | 'RESISTOR, SINGLE,196KOHM,THICK FILM,1%,200V,.25,-55/125C,1206'                         | 'NFND'    
 'CL1001017A'    | '2.15KOHM'   | '1%'         = 'SMC_1206R'          | '(SMC_1206R)'                          | 'RESISTOR, SINGLE,2.15KOHM,THICK FILM,1%,200V,.25,-55/125C,1206'                        | 'NFND'    
 'CL1001018A'    | '21.5KOHM'   | '1%'         = 'SMC_1206R'          | '(SMC_1206R)'                          | 'RESISTOR, SINGLE,21.5KOHM,THICK FILM,1%,200V,.25,-55/125C,1206'                        | 'NFND'    
 'CL1001019A'    | '21.5OHM'    | '1%'         = 'SMC_1206R'          | '(SMC_1206R)'                          | 'RESISTOR, SINGLE,21.5OHM,THICK FILM,1%,200V,.25,-55/125C,1206'                         | 'NFND'    
 'CL1001020A'    | '237OHM'     | '1%'         = 'SMC_1206R'          | '(SMC_1206R)'                          | 'RESISTOR, SINGLE,237OHM,THICK FILM,1%,200V,.25,-55/125C,1206'                          | 'NFND'    
 'CL1001021A'    | '2.37KOHM'   | '1%'         = 'SMC_1206R'          | '(SMC_1206R)'                          | 'RESISTOR, SINGLE,2.37KOHM,THICK FILM,1%,200V,.25,-55/125C,1206'                        | 'NFND'    
 'CL1001022A'    | '23.7KOHM'   | '1%'         = 'SMC_1206R'          | '(SMC_1206R)'                          | 'RESISTOR, SINGLE,23.7KOHM,THICK FILM,1%,200V,.25,-55/125C,1206'                        | 'NFND'    
 'CL1001023A'    | '23.7OHM'    | '1%'         = 'SMC_1206R'          | '(SMC_1206R)'                          | 'RESISTOR, SINGLE,23.7OHM,THICK FILM,1%,200V,.25,-55/125C,1206'                         | 'NFND'    
 'CL1001024A'    | '24.9KOHM'   | '1%'         = 'SMC_1206R'          | '(SMC_1206R)'                          | 'RESISTOR, SINGLE,24.9KOHM,THICK FILM,1%,200V,.25,-55/125C,1206'                        | 'NFND'    
 'CL1001025A'    | '24.9OHM'    | '1%'         = 'SMC_1206R'          | '(SMC_1206R)'                          | 'RESISTOR, SINGLE,24.9OHM,THICK FILM,1%,200V,.25,-55/125C,1206'                         | 'NFND'    
 'CL1001026A'    | '261KOHM'    | '1%'         = 'SMC_1206R'          | '(SMC_1206R)'                          | 'RESISTOR, SINGLE,261KOHM,THICK FILM,1%,200V,.25,-55/125C,1206'                         | 'NFND'    
 'CL1001027A'    | '26.1OHM'    | '1%'         = 'SMC_1206R'          | '(SMC_1206R)'                          | 'RESISTOR, SINGLE,26.1OHM,THICK FILM,1%,200V,.25,-55/125C,1206'                         | 'NFND'    
 'CL1001028A'    | '2.74KOHM'   | '1%'         = 'SMC_1206R'          | '(SMC_1206R)'                          | 'RESISTOR, SINGLE,2.74KOHM,THICK FILM,1%,200V,.25,-55/125C,1206'                        | 'NFND'    
 'CL1001029A'    | '287OHM'     | '1%'         = 'SMC_1206R'          | '(SMC_1206R)'                          | 'RESISTOR, SINGLE,287OHM,THICK FILM,1%,200V,.25,-55/125C,1206'                          | 'NFND'    
 'CL1001030A'    | '2.87KOHM'   | '1%'         = 'SMC_1206R'          | '(SMC_1206R)'                          | 'RESISTOR, SINGLE,2.87KOHM,THICK FILM,1%,200V,.25,-55/125C,1206'                        | 'NFND'    
 'CL1001031A'    | '28.7KOHM'   | '1%'         = 'SMC_1206R'          | '(SMC_1206R)'                          | 'RESISTOR, SINGLE,28.7KOHM,THICK FILM,1%,200V,.25,-55/125C,1206'                        | 'NFND'    
 'CL1001032A'    | '28.7OHM'    | '1%'         = 'SMC_1206R'          | '(SMC_1206R)'                          | 'RESISTOR, SINGLE,28.7OHM,THICK FILM,1%,200V,.25,-55/125C,1206'                         | 'NFND'    
 'CL1001033A'    | '3.16KOHM'   | '1%'         = 'SMC_1206R'          | '(SMC_1206R)'                          | 'RESISTOR, SINGLE,3.16KOHM,THICK FILM,1%,200V,.25,-55/125C,1206'                        | 'NFND'    
 'CL1001034A'    | '31.6KOHM'   | '1%'         = 'SMC_1206R'          | '(SMC_1206R)'                          | 'RESISTOR, SINGLE,31.6KOHM,THICK FILM,1%,200V,.25,-55/125C,1206'                        | 'NFND'    
 'CL1001035A'    | '316KOHM'    | '1%'         = 'SMC_1206R'          | '(SMC_1206R)'                          | 'RESISTOR, SINGLE,316KOHM,THICK FILM,1%,200V,.25,-55/125C,1206'                         | 'NFND'    
 'CL1001036A'    | '31.6OHM'    | '1%'         = 'SMC_1206R'          | '(SMC_1206R)'                          | 'RESISTOR, SINGLE,31.6OHM,THICK FILM,1%,200V,.25,-55/125C,1206'                         | 'NFND'    
 'CL1001037A'    | '332OHM'     | '1%'         = 'SMC_1206R'          | '(SMC_1206R)'                          | 'RESISTOR, SINGLE,332OHM,THICK FILM,1%,200V,.25,-55/125C,1206'                          | 'NFND'    
 'CL1001038A'    | '33.2KOHM'   | '1%'         = 'SMC_1206R'          | '(SMC_1206R)'                          | 'RESISTOR, SINGLE,33.2KOHM,THICK FILM,1%,200V,.25,-55/125C,1206'                        | 'NFND'    
 'CL1001039A'    | '348OHM'     | '1%'         = 'SMC_1206R'          | '(SMC_1206R)'                          | 'RESISTOR, SINGLE,348OHM,THICK FILM,1%,200V,.25,-55/125C,1206'                          | 'NFND'    
 'CL1001040A'    | '34.8KOHM'   | '1%'         = 'SMC_1206R'          | '(SMC_1206R)'                          | 'RESISTOR, SINGLE,34.8KOHM,THICK FILM,1%,200V,.25,-55/125C,1206'                        | 'NFND'    
 'CL1001041A'    | '3.83KOHM'   | '1%'         = 'SMC_1206R'          | '(SMC_1206R)'                          | 'RESISTOR, SINGLE,3.83KOHM,THICK FILM,1%,200V,.25,-55/125C,1206'                        | 'NFND'    
 'CL1001042A'    | '383KOHM'    | '1%'         = 'SMC_1206R'          | '(SMC_1206R)'                          | 'RESISTOR, SINGLE,383KOHM,THICK FILM,1%,200V,.25,-55/125C,1206'                         | 'NFND'    
 'CL1001043A'    | '38.3OHM'    | '1%'         = 'SMC_1206R'          | '(SMC_1206R)'                          | 'RESISTOR, SINGLE,38.3OHM,THICK FILM,1%,200V,.25,-55/125C,1206'                         | 'NFND'    
 'CL1001044A'    | '422OHM'     | '1%'         = 'SMC_1206R'          | '(SMC_1206R)'                          | 'RESISTOR, SINGLE,422OHM,THICK FILM,1%,200V,.25,-55/125C,1206'                          | 'NFND'    
 'CL1001045A'    | '4.22KOHM'   | '1%'         = 'SMC_1206R'          | '(SMC_1206R)'                          | 'RESISTOR, SINGLE,4.22KOHM,THICK FILM,1%,200V,.25,-55/125C,1206'                        | 'NFND'    
 'CL1001046A'    | '42.2KOHM'   | '1%'         = 'SMC_1206R'          | '(SMC_1206R)'                          | 'RESISTOR, SINGLE,42.2KOHM,THICK FILM,1%,200V,.25,-55/125C,1206'                        | 'NFND'    
 'CL1001047A'    | '464OHM'     | '1%'         = 'SMC_1206R'          | '(SMC_1206R)'                          | 'RESISTOR, SINGLE,464OHM,THICK FILM,1%,200V,.25,-55/125C,1206'                          | 'NFND'    
 'CL1001048A'    | '4.64KOHM'   | '1%'         = 'SMC_1206R'          | '(SMC_1206R)'                          | 'RESISTOR, SINGLE,4.64KOHM,THICK FILM,1%,200V,.25,-55/125C,1206'                        | 'NFND'    
 'CL1001049A'    | '46.4OHM'    | '1%'         = 'SMC_1206R'          | '(SMC_1206R)'                          | 'RESISTOR, SINGLE,46.4OHM,THICK FILM,1%,200V,.25,-55/125C,1206'                         | 'NFND'    
 'CL1001050A'    | '5.11KOHM'   | '1%'         = 'SMC_1206R'          | '(SMC_1206R)'                          | 'RESISTOR, SINGLE,5.11KOHM,THICK FILM,1%,200V,.25,-55/125C,1206'                        | 'NFND'    
 'CL1001051A'    | '51.1KOHM'   | '1%'         = 'SMC_1206R'          | '(SMC_1206R)'                          | 'RESISTOR, SINGLE,51.1KOHM,THICK FILM,1%,200V,.25,-55/125C,1206'                        | 'NFND'    
 'CL1001052A'    | '511KOHM'    | '1%'         = 'SMC_1206R'          | '(SMC_1206R)'                          | 'RESISTOR, SINGLE,511KOHM,THICK FILM,1%,200V,.25,-55/125C,1206'                         | 'NFND'    
 'CL1001053A'    | '51.1OHM'    | '1%'         = 'SMC_1206R'          | '(SMC_1206R)'                          | 'RESISTOR, SINGLE,51.1OHM,THICK FILM,1%,200V,.25,-55/125C,1206'                         | 'NFND'    
 'CL1001054A'    | '56.2OHM'    | '1%'         = 'SMC_1206R'          | '(SMC_1206R)'                          | 'RESISTOR, SINGLE,56.2OHM,THICK FILM,1%,200V,.25,-55/125C,1206'                         | 'NFND'    
 'CL1001055A'    | '619OHM'     | '1%'         = 'SMC_1206R'          | '(SMC_1206R)'                          | 'RESISTOR, SINGLE,619OHM,THICK FILM,1%,200V,.25,-55/125C,1206'                          | 'NFND'    
 'CL1001056A'    | '6.19KOHM'   | '1%'         = 'SMC_1206R'          | '(SMC_1206R)'                          | 'RESISTOR, SINGLE,6.19KOHM,THICK FILM,1%,200V,.25,-55/125C,1206'                        | 'NFND'    
 'CL1001057A'    | '681OHM'     | '1%'         = 'SMC_1206R'          | '(SMC_1206R)'                          | 'RESISTOR, SINGLE,681OHM,THICK FILM,1%,200V,.25,-55/125C,1206'                          | 'NFND'    
 'CL1001058A'    | '6.81KOHM'   | '1%'         = 'SMC_1206R'          | '(SMC_1206R)'                          | 'RESISTOR, SINGLE,6.81KOHM,THICK FILM,1%,200V,.25,-55/125C,1206'                        | 'NFND'    
 'CL1001059A'    | '68.1KOHM'   | '1%'         = 'SMC_1206R'          | '(SMC_1206R)'                          | 'RESISTOR, SINGLE,68.1KOHM,THICK FILM,1%,200V,.25,-55/125C,1206'                        | 'NFND'    
 'CL1001060A'    | '68.1OHM'    | '1%'         = 'SMC_1206R'          | '(SMC_1206R)'                          | 'RESISTOR, SINGLE,68.1OHM,THICK FILM,1%,200V,.25,-55/125C,1206'                         | 'NFND'    
 'CL1001061A'    | '7.15KOHM'   | '1%'         = 'SMC_1206R'          | '(SMC_1206R)'                          | 'RESISTOR, SINGLE,7.15KOHM,THICK FILM,1%,200V,.25,-55/125C,1206'                        | 'NFND'    
 'CL1001062A'    | '750OHM'     | '1%'         = 'SMC_1206R'          | '(SMC_1206R)'                          | 'RESISTOR, SINGLE,750OHM,THICK FILM,1%,200V,.25,-55/125C,1206'                          | 'NFND'    
 'CL1001063A'    | '75KOHM'     | '1%'         = 'SMC_1206R'          | '(SMC_1206R)'                          | 'RESISTOR, SINGLE,75KOHM,THICK FILM,1%,200V,.25,-55/125C,1206'                          | 'NFND'    
 'CL1001064A'    | '75OHM'      | '1%'         = 'SMC_1206R'          | '(SMC_1206R)'                          | 'RESISTOR, SINGLE,75OHM,THICK FILM,1%,200V,.25,-55/125C,1206'                           | 'NFND'    
 'CL1001065A'    | '8.25KOHM'   | '1%'         = 'SMC_1206R'          | '(SMC_1206R)'                          | 'RESISTOR, SINGLE,8.25,KOHM,THICK FILM,1%,200V,.25,-55/125C,1206'                       | 'NFND'    
 'CL1001066A'    | '82.5KOHM'   | '1%'         = 'SMC_1206R'          | '(SMC_1206R)'                          | 'RESISTOR, SINGLE,82.5KOHM,THICK FILM,1%,200V,.25,-55/125C,1206'                        | 'NFND'    
 'CL1001067A'    | '90.9KOHM'   | '1%'         = 'SMC_1206R'          | '(SMC_1206R)'                          | 'RESISTOR, SINGLE,90.9KOHM,THICK FILM,1%,200V,.25,-55/125C,1206'                        | 'NFND'    
 'CL1001068A'    | '90.9OHM'    | '1%'         = 'SMC_1206R'          | '(SMC_1206R)'                          | 'RESISTOR, SINGLE,90.9OHM,THICK FILM,1%,200V,.25,-55/125C,1206'                         | 'NFND'    
 'CL1001069A'    | '196OHM'     | '1%'         = 'SMC_1206R'          | '(SMC_1206R)'                          | 'RESISTOR, SINGLE,196OHM,THICK FILM,1%,200V,.25,-55/125C,1206'                          | 'NFND'    
 'CL1001070A'    | '46.4KOHM'   | '1%'         = 'SMC_1206R'          | '(SMC_1206R)'                          | 'RESISTOR, SINGLE,46.4KOHM,THICK FILM,1%,200V,.25,-55/125C,1206'                        | 'NFND'    
 'CL1001071A'    | '511OHM'     | '1%'         = 'SMC_1206R'          | '(SMC_1206R)'                          | 'RESISTOR, SINGLE,511OHM,THICK FILM,1%,200V,.25,-55/125C,1206'                          | 'NFND'    
 'CL1001072A'    | '100OHM'     | '1%'         = 'SMC_1206R'          | '(SMC_1206R)'                          | 'RESISTOR, SINGLE,100OHM,THICK FILM,1%,200V,.25,-55/125C,1206'                          | 'NFND'    
 'CL1001073A'    | '11OHM'      | '1%'         = 'SMC_1206R'          | '(SMC_1206R)'                          | 'RESISTOR, SINGLE,11OHM,THICK FILM,1%,200V,.25,-55/125C,1206'                           | 'NFND'    
 'CL1001074A'    | '1.33KOHM'   | '1%'         = 'SMC_1206R'          | '(SMC_1206R)'                          | 'RESISTOR, SINGLE,1.33KOHM,THICK FILM,1%,200V,.25,-55/125C,1206'                        | 'NFND'    
 'CL1001075A'    | '147OHM'     | '1%'         = 'SMC_1206R'          | '(SMC_1206R)'                          | 'RESISTOR, SINGLE,147OHM,THICK FILM,1%,200V,.25,-55/125C,1206'                          | 'NFND'    
 'CL1001076A'    | '14.7OHM'    | '1%'         = 'SMC_1206R'          | '(SMC_1206R)'                          | 'RESISTOR, SINGLE,14.7OHM,THICK FILM,1%,200V,.25,-55/125C,1206'                         | 'NFND'    
 'CL1001077A'    | '215OHM'     | '1%'         = 'SMC_1206R'          | '(SMC_1206R)'                          | 'RESISTOR, SINGLE,215OHM,THICK FILM,1%,200V,.25,-55/125C,1206'                          | 'NFND'    
 'CL1001078A'    | '261OHM'     | '1%'         = 'SMC_1206R'          | '(SMC_1206R)'                          | 'RESISTOR, SINGLE,261OHM,THICK FILM,1%,200V,.25,-55/125C,1206'                          | 'NFND'    
 'CL1001079A'    | '26.1KOHM'   | '1%'         = 'SMC_1206R'          | '(SMC_1206R)'                          | 'RESISTOR, SINGLE,26.1KOHM,THICK FILM,1%,200V,.25,-55/125C,1206'                        | 'NFND'    
 'CL1001080A'    | '316OHM'     | '1%'         = 'SMC_1206R'          | '(SMC_1206R)'                          | 'RESISTOR, SINGLE,316OHM,THICK FILM,1%,200V,.25,-55/125C,1206'                          | 'NFND'    
 'CL1001081A'    | '365OHM'     | '1%'         = 'SMC_1206R'          | '(SMC_1206R)'                          | 'RESISTOR, SINGLE,365OHM,THICK FILM,1%,200V,.25,-55/125C,1206'                          | 'NFND'    
 'CL1001082A'    | '3.65KOHM'   | '1%'         = 'SMC_1206R'          | '(SMC_1206R)'                          | 'RESISTOR, SINGLE,3.65KOHM,THICK FILM,1%,200V,.25,-55/125C,1206'                        | 'NFND'    
 'CL1001083A'    | '38.3KOHM'   | '1%'         = 'SMC_1206R'          | '(SMC_1206R)'                          | 'RESISTOR, SINGLE,38.3KOHM,THICK FILM,1%,200V,.25,-55/125C,1206'                        | 'NFND'    
 'CL1001084A'    | '422KOHM'    | '1%'         = 'SMC_1206R'          | '(SMC_1206R)'                          | 'RESISTOR, SINGLE,422KOHM,THICK FILM,1%,200V,.25,-55/125C,1206'                         | 'NFND'    
 'CL1001085A'    | '44.2OHM'    | '1%'         = 'SMC_1206R'          | '(SMC_1206R)'                          | 'RESISTOR, SINGLE,44.2OHM,THICK FILM,1%,200V,.25,-55/125C,1206'                         | 'NFND'    
 'CL1001086A'    | '562OHM'     | '1%'         = 'SMC_1206R'          | '(SMC_1206R)'                          | 'RESISTOR, SINGLE,562OHM,THICK FILM,1%,200V,.25,-55/125C,1206'                          | 'NFND'    
 'CL1001087A'    | '61.9OHM'    | '1%'         = 'SMC_1206R'          | '(SMC_1206R)'                          | 'RESISTOR, SINGLE,61.9OHM,THICK FILM,1%,200V,.25,-55/125C,1206'                         | 'NFND'    
 'CL1001088A'    | '7.5KOHM'    | '1%'         = 'SMC_1206R'          | '(SMC_1206R)'                          | 'RESISTOR, SINGLE,7.5KOHM,THICK FILM,1%,200V,.25,-55/125C,1206'                         | 'NFND'    
 'CL1001089A'    | '825OHM'     | '1%'         = 'SMC_1206R'          | '(SMC_1206R)'                          | 'RESISTOR, SINGLE,825OHM,THICK FILM,1%,200V,.25,-55/125C,1206'                          | 'NFND'    
 'CL1001090A'    | '909OHM'     | '1%'         = 'SMC_1206R'          | '(SMC_1206R)'                          | 'RESISTOR, SINGLE,909OHM,THICK FILM,1%,200V,.25,-55/125C,1206'                          | 'NFND'    
 'CL1001091A'    | '9.31KOHM'   | '1%'         = 'SMC_1206R'          | '(SMC_1206R)'                          | 'RESISTOR, SINGLE,9.31KOHM,THICK FILM,1%,200V,.25,-55/125C,1206'                        | 'NFND'    
 'CL1001092A'    | '9.09OHM'    | '1%'         = 'SMC_1206R'          | '(SMC_1206R)'                          | 'RESISTOR, SINGLE,9.09OHM,THICK FILM,1%,200V,.25,-55/125C,1206'                         | 'NFND'    
 'CL1001093A'    | '100OHM'     | '1%'         = 'SMC_1206R'          | '(SMC_1206R)'                          | 'RESISTOR, SINGLE,100OHM,THICK FILM,1%,200V,.25,-55/125C,SMD,1206'                      | 'NFND'    
 'CL1001094A'    | '1.1KOHM'    | '1%'         = 'SMC_1206R'          | '(SMC_1206R)'                          | 'RESISTOR, SINGLE,1.1KOHM,THICK FILM,1%,200V,.25,-55/125C,SMD,1206'                     | 'NFND'    
 'CL1001095A'    | '11.5OHM'    | '1%'         = 'SMC_1206R'          | '(SMC_1206R)'                          | 'RESISTOR, SINGLE,11.5OHM,THICK FILM,1%,200V,.25,-55/125C,SMD,1206'                     | 'NFND'    
 'CL1001096A'    | '100OHM'     | '1%'         = 'SMC_1210R'          | '(SMC_1210R)'                          | 'RESISTOR, SINGLE,100OHM,THICK FILM,1%,200V,.5W,-55/125C,1210'                          | 'NFND'    
 'CL1001097A'    | '10OHM'      | '1%'         = 'SMC_1210R'          | '(SMC_1210R)'                          | 'RESISTOR, SINGLE,10OHM,THICK FILM,1%,200V,.5W,-55/125C,1210'                           | 'NFND'    
 'CL1001098A'    | '332OHM'     | '1%'         = 'SMC_1210R'          | '(SMC_1210R)'                          | 'RESISTOR, SINGLE,332OHM,THICK FILM,1%,200V,.5W,-55/125C,1210'                          | 'NFND'    
 'CL1001099A'    | '681OHM'     | '1%'         = 'SMC_2010R'          | '(SMC_2010R)'                          | 'RESISTOR, SINGLE,681OHM,THICK FILM,1%,.5W,-55/125C,2010'                               | 'NFND'    
 'CL1001100A'    | '365OHM'     | '1%'         = 'SMC_2010R'          | '(SMC_2010R)'                          | 'RESISTOR, SINGLE,365OHM,THICK FILM,1%,.5W,-55/125C,SMD,2010'                           | 'NFND'    
 'CL1001101A'    | '0OHM'       | '-'          = 'SMC_0402R'          | '(SMC_0402R_C)'                        | 'RESISTOR, SINGLE,0OHM,THICK FILM,-55/125C,0402'                                        | 'NFND'    
 'G152-00052-01' | '0OHM'       | '-'          = 'SMC_0402R'          | '(SMC_0402R_C)'                        | 'RESISTOR, SINGLE,0OHM,THICK FILM,-55/125C,0402'                                        | ''        
 'CL1001102A'    | '0OHM'       | '-'          = 'SMC_0603R'          | '(SMC_0603R)'                          | 'RESISTOR, SINGLE,0OHM,THICK FILM,-55/125C,0603'                                        | 'NFND'    
 'G152-00051-01' | '0OHM'       | '-'          = 'SMC_0603R'          | '(SMC_0603R)'                          | 'RESISTOR, SINGLE,0OHM,THICK FILM,-55/125C,0603'                                        | ''        
 'CL1001103A'    | '0OHM'       | '-'          = 'SMC_0805R'          | '(SMC_0805R)'                          | 'RESISTOR, SINGLE,0OHM,THICK FILM,-55/125C,0805'                                        | 'NFND'    
 'CL1001104A'    | '0OHM'       | '-'          = 'SMC_1206R'          | '(SMC_1206R)'                          | 'RESISTOR, SINGLE,0OHM,THICK FILM,-55/125C,1206'                                        | 'NFND'    
 'G158-00R00-05' | '0OHM'       | '-'          = 'SMC_1206R'          | '(SMC_1206R)'                          | 'RESISTOR, SINGLE,0OHM,THICK FILM,-55/125C,1206'                                        | ''        
 'CL1001105A'    | '10KOHM'     | '0.10%'      = 'SMC_0805R'          | '(SMC_0805R)'                          | 'RESISTOR, SINGLE,10KOHM,THICK FILM,.1%,100V,.1W,-55/125C,0805'                         | 'NFND'    
 'CL1001106A'    | '511OHM'     | '0.10%'      = 'SMC_0805R'          | '(SMC_0805R)'                          | 'RESISTOR, SINGLE,511OHM,THIN FILM,.1%,100V,.1W,-55/125C,0805'                          | 'NFND'    
 'CL1001107A'    | '100KOHM'    | '0.10%'      = 'SMC_1206R'          | '(SMC_1206R)'                          | 'RESISTOR, SINGLE,100KOHM,THICK FILM,.1%,150V,.125W,-55/125C,1206'                      | 'NFND'    
 'CL1001108A'    | '0.301OHM'   | '1%'         = 'SMC_1206R'          | '(SMC_1206R)'                          | 'RESISTOR, SINGLE,0.301OHM,THICK FILM,1%,.33W,-55/125C,SMD,1206'                        | 'NFND'    
 'CL1001322A'    | '1.24KOHM'   | '1%'         = 'SMC_0402R'          | '(SMC_0402R_C)'                        | 'RESISTOR, SINGLE,1.24KOHM,THICK FILM,1%,50V,.063W.-55/125C,0402'                       | 'NFND'    
 'G152-00053-01' | '1.24KOHM'   | '1%'         = 'SMC_0402R'          | '(SMC_0402R_C)'                        | 'RESISTOR, SINGLE,1.24KOHM,THICK FILM,1%,50V,.063W.-55/125C,0402'                       | ''        
 'CL1001326A'    | '39OHM'      | '1%'         = 'SMC_0402R'          | '(SMC_0402R_C)'                        | 'RESISTOR, SINGLE,39OHM,THICK FILM,1%,50V,.063W,-55/125C,0402'                          | 'NFND'    
 'CL1001327A'    | '33.2OHM'    | '1%'         = 'SMC_0402R'          | '(SMC_0402R_C)'                        | 'RESISTOR, SINGLE,33.2OHM,THICK FILM,1%,50V,.063W,-55/125C,0402'                        | 'NFND'    
 'CL1001328A'    | '22OHM'      | '1%'         = 'SMC_0402R'          | '(SMC_0402R_C)'                        | 'RESISTOR,SINGLE,22OHM,THICK FILM,1%,50V,.063W,-55/125C,0402'                           | 'NFND'    
 'G152-00054-01' | '22OHM'      | '1%'         = 'SMC_0402R'          | '(SMC_0402R_C)'                        | 'RESISTOR,SINGLE,22OHM,THICK FILM,1%,50V,.063W,-55/125C,0402'                           | 'NFND'    
 'CL1001332A'    | '33OHM'      | '1%'         = 'SMC_0402R'          | '(SMC_0402R_C)'                        | 'RESISTOR,SINGLE,33OHM,THICK FILM,1%,50V,.063W,-55/125C,0402'                           | 'NFND'    
 'G152-00037-01' | '33OHM'      | '1%'         = 'SMC_0402R'          | '(SMC_0402R_C)'                        | 'RESISTOR,SINGLE,33OHM,THICK FILM,1%,50V,.063W,-55/125C,0402'                           | ''        
 'CL1001333A'    | '49.9OHM'    | '1%'         = 'SMC_0402R'          | '(SMC_0402R_C)'                        | 'RESISTOR,SINGLE,49.9OHM,THICK FILM,1%,50V,.063W,-55/125C,0402'                         | 'NFND'    
 'G152-00038-01' | '49.9OHM'    | '1%'         = 'SMC_0402R'          | '(SMC_0402R_C)'                        | 'RESISTOR,SINGLE,49.9OHM,THICK FILM,1%,50V,.063W,-55/125C,0402'                         | ''        
 'CL1001334A'    | '475OHM'     | '1%'         = 'SMC_0402R'          | '(SMC_0402R_C)'                        | 'RESISTOR,SINGLE,475OHM,THICK FILM,1%,50V,.063W,-55/125C,0402'                          | 'NFND'    
 'G152-00036-01' | '475OHM'     | '1%'         = 'SMC_0402R'          | '(SMC_0402R_C)'                        | 'RESISTOR,SINGLE,475OHM,THICK FILM,1%,50V,.063W,-55/125C,0402'                          | ''        
 'CL1001335A'    | '150OHM'     | '1%'         = 'SMC_0402R'          | '(SMC_0402R_C)'                        | 'RESISTOR,SINGLE,150OHM,THICK FILM,1%,50V,.063W,-55/125C,0402'                          | 'NFND'    
 'G152-00039-01' | '150OHM'     | '1%'         = 'SMC_0402R'          | '(SMC_0402R_C)'                        | 'RESISTOR,SINGLE,150OHM,THICK FILM,1%,50V,.063W,-55/125C,0402'                          | ''        
 'CL1001336A'    | '18.2OHM'    | '1%'         = 'SMC_0402R'          | '(SMC_0402R_C)'                        | 'RESISTOR,SINGLE,18.2OHM,THCIK FILM,1%,50V,.063W,-55/125C,0402'                         | 'NFND'    
 'CL1001337A'    | '33OHM'      | '1%'         = 'SMC_0603R'          | '(SMC_0603R)'                          | 'RESISTOR,SINGLE,33OHM,THICK FILM,1%,50V,.1W,-55/125V,0603'                             | 'NFND'    
 'CL1001338A'    | '18.2OHM'    | '1%'         = 'SMC_0603R'          | '(SMC_0603R)'                          | 'RESISTOR,SINGLE,18.2OHM,THICK FILM,1%,50V,.1W,-55/125C,0603'                           | 'NFND'    
 'CL1001356A'    | '200OHM'     | '1%'         = 'SMC_0603R'          | '(SMC_0603R)'                          | 'RESISTOR,SINGLE,200OHM,THICK FILM,1%,50V,.1W,-55/125C.0603'                            | 'NFND'    
 'CL1001357A'    | '300OHM'     | '1%'         = 'SMC_0603R'          | '(SMC_0603R)'                          | 'RESISTOR,SINGLE,300OHM,THICK FILM,1%,50V,.1W,-55/125C.0603'                            | 'NFND'    
 'CL1001366A'    | '200OHM'     | '1%'         = 'SMC_0402R'          | '(SMC_0402R_C)'                        | 'RESISTOR,SINGLE,200OHM,THICK FILM,1%,50V,.063W,-55/125C,0402'                          | 'NFND'    
 'G152-00040-01' | '200OHM'     | '1%'         = 'SMC_0402R'          | '(SMC_0402R_C)'                        | 'RESISTOR,SINGLE,200OHM,THICK FILM,1%,50V,.063W,-55/125C,0402'                          | ''        
 'CL1001370A'    | '2.4KOHM'    | '1%'         = 'SMC_0402R'          | '(SMC_0402R_C)'                        | 'RESISTOR,SINGLE,2.4KOHM,THCIK FILM,1%,50V,.063W,-55/125C,0402'                         | 'NFND'    
 'CL1001371A'    | '2KOHM'      | '1%'         = 'SMC_0402R'          | '(SMC_0402R_C)'                        | 'RESISTOR,SINGLE,2KOHM,THCIK FILM,1%,50V,.063W,-55/125C,0402'                           | 'NFND'    
 'CL1001422A'    | '3.57KOHM'   | '1%'         = 'SMC_0603R'          | '(SMC_0603R)'                          | 'RESISTOR, SINGLE, 3.57KOHM, THICK FILM, 1%, 50V, .1W, -55/125C, 0603'                  | 'NFND'    
 'CL1001423A'    | '3.9KOHM'    | '0.5%'       = 'SMC_0603R'          | '(SMC_0603R)'                          | 'RESISTOR, SINGLE, 3.9KOHM, THICK FILM, 0.5%, 50V, .1W, -55/125C, 0603'                 | 'NFND'    
 'G152-00043-01' | '3.9KOHM'    | '0.5%'       = 'SMC_0603R_H022'     | '(SMC_0603R_H022)'                     | 'RESISTOR, SINGLE, 3.9KOHM, THICK FILM, 0.5%, 50V, .1W, -55/125C, 0603'                 | ''        
 'CL1001441A'    | '4.99KOHM'   | '1%'         = 'SMC_0603R'          | '(SMC_0603R)'                          | 'RESISTOR, SINGLE, 4.99KOHM, THICK FILM, 1%, 50V, .1W, -55/125C, 0603'                  | 'NFND'    
 'CL1001442A'    | '0.01OHM'    | '1%'         = 'SMC_1206R'          | '(SMC_1206R)'                          | 'RESISTOR, SINGLE, 0.01OHM, THICK FILM, 1%, .5W, -55/125C, 1206'                        | 'NFND'    
 'CL1001443A'    | '1.13KOHM'   | '1%'         = 'SMC_0603R'          | '(SMC_0603R)'                          | 'RESISTOR, SINGLE, 1.13KOHM, THICK FILM, 1%, 50V, .1W, -55/125C, 0603'                  | 'NFND'    
 'CL1001444A'    | '4.53KOHM'   | '1%'         = 'SMC_0603R'          | '(SMC_0603R)'                          | 'RESISTOR, SINGLE, 4.53KOHM, THICK FILM, 1%, 50V, .1W, -55/125C, 0603'                  | 'NFND'    
 'CL1001445A'    | '3.3KOHM'    | '1%'         = 'SMC_0603R'          | '(SMC_0603R)'                          | 'RESISTOR, SINGLE, 3.3KOHM, THICK FILM, 1%, 50V, .1W, -55/125C, 0603'                   | 'NFND'    
 'CL1001446A'    | '4.12KOHM'   | '1%'         = 'SMC_0603R'          | '(SMC_0603R)'                          | 'RESISTOR, SINGLE, 4.12KOHM, THICK FILM, 1%, 50V, .1W, -55/125C, 0603'                  | 'NFND'    
 'CL1001447A'    | '4.75KOHM'   | '1%'         = 'SMC_0603R'          | '(SMC_0603R)'                          | 'RESISTOR, SINGLE, 4.75KOHM, THICK FILM, 1%, 50V, .1W, -55/125C, 0603'                  | 'NFND'    
 'CL1001448A'    | '1.2KOHM'    | '1%'         = 'SMC_0603R'          | '(SMC_0603R)'                          | 'RESISTOR, SINGLE, 1.2KOHM, THICK FILM, 1%, 50V, .1W, -55/125C, 0603'                   | 'NFND'    
 'CL1001435A'    | '5.9KOHM'    | '1%'         = 'SMC_0402R'          | '(SMC_0402R_C)'                        | 'RESISTOR, SINGLE, 5.9KOHM, THICK FILM, 1%, 50V, .063W, -55/125C, 0402'                 | 'NFND'    
 'CL1001436A'    | '8.66KOHM'   | '1%'         = 'SMC_0402R'          | '(SMC_0402R_C)'                        | 'RESISTOR, SINGLE, 8.66KOHM, THICK FILM, 1%, 50V, .063W, -55/125C, 0402'                | 'NFND'    
 'CL1001449A'    | '3.2KOHM'    | '1%'         = 'SMC_0402R'          | '(SMC_0402R_C)'                        | 'RESISTOR, SINGLE,3.2KOHM,THICK FILM,1%,50V,.063W,-55/125C,0402'                        | 'NFND'    
 'CL1001450A'    | '1.87KOHM'   | '1%'         = 'SMC_0402R'          | '(SMC_0402R_C)'                        | 'RESISTOR, SINGLE,1.87KOHM,THICK FILM,1%,50V,.063W,-55/125C,0402'                       | 'NFND'    
 'CL1001451A'    | '1.13KOHM'   | '1%'         = 'SMC_0402R'          | '(SMC_0402R_C)'                        | 'RESISTOR, SINGLE,1.13KOHM,THICK FILM,1%,50V,.063W,-55/125C,0402'                       | 'NFND'    
 'G152-00055-01' | '1.13KOHM'   | '1%'         = 'SMC_0402R'          | '(SMC_0402R_C)'                        | 'RESISTOR, SINGLE,1.13KOHM,THICK FILM,1%,50V,.063W,-55/125C,0402'                       | ''        
 'CL1001452A'    | '4.53KOHM'   | '1%'         = 'SMC_0402R'          | '(SMC_0402R_C)'                        | 'RESISTOR, SINGLE,4.53KOHM,THICK FILM,1%,50V,.063W,-55/125C,0402'                       | 'NFND'    
 'G152-00059-01' | '4.99KOHM'   | '1%'         = 'SMC_0402R'          | '(SMC_0402R_C)'                        | 'RESISTOR, SINGLE,4.99KOHM,THICK FILM,1%,50V,.063W,-55/125C,0402'                       | ''        
 'CL1001375A'    | '180OHM'     | '1%'         = 'SMC_0402R'          | '(SMC_0402R_C)'                        | 'RESISTOR, SINGLE, 180OHM, THICK FILM, 1%, 50V, .063W, -55/125C, 0402'                  | 'NFND'    
 'CL1001376A'    | '732OHM'     | '1%'         = 'SMC_0603R'          | '(SMC_0603R)'                          | 'RESISTOR, SINGLE, 732OHM, THICK FILM, 1%, 50V, .1W, -55/125C, 0603'                    | 'NFND'    
 'CL1001377A'    | '7.68KOHM'   | '1%'         = 'SMC_0603R'          | '(SMC_0603R)'                          | 'RESISTOR, SINGLE, 7.68KOHM, THICK FILM, 1%, 50V, .1W, -55/125C, 0603'                  | 'NFND'    
 'CL1001473A'    | '270OHM'     | '1%'         = 'SMC_0402R'          | '(SMC_0402R_C)'                        | 'RESISTOR, SINGLE, 270OHM, THICK FILM, 1%, 50V, .063W, -55/125C, 0402'                  | 'NFND'    
 'CL1001474A'    | '2OHM'       | '1%'         = 'SMC_0402R'          | '(SMC_0402R_C)'                        | 'RESISTOR, SINGLE, 2OHM, THICK FILM, 1%, .125W, -55/150C, 0402'                         | 'NFND'    
 'CL1001475A'    | '1.43KOHM'   | '1%'         = 'SMC_0603R'          | '(SMC_0603R)'                          | 'RESISTOR, SINGLE, 1.43KOHM, THICK FILM, 1%, 50V, .1W, -55/125C, 0603'                  | 'NFND'    
 'G152-00033-01' | '1.43KOHM'   | '1%'         = 'SMC_0603R'          | '(SMC_0603R)'                          | 'RESISTOR, SINGLE, 1.43KOHM, THICK FILM, 1%, 50V, .1W, -55/125C, 0603'                  | ''        
 'CL1003508A'    | '379OHM'     | '0.5%'       = 'SMC_0402R'          | '(SMC_0402R_C)'                        | 'RESISTOR, SINGLE, 379OHM, THICK FILM, 0.5%, 50V, .063W, -55/125C, 0402'                | 'NFND'    
 'CL1003509A'    | '604OHM'     | '0.5%'       = 'SMC_0402R'          | '(SMC_0402R_C)'                        | 'RESISTOR, SINGLE, 604OHM, THICK FILM, 0.5%, 50V, .063W, -55/125C, 0402'                | 'NFND'    
 'CL1003510A'    | '1.1KOHM'    | '0.5%'       = 'SMC_0402R'          | '(SMC_0402R_C)'                        | 'RESISTOR, SINGLE, 1.1KOHM, THICK FILM, 0.5%, 50V, .063W, -55/125C, 0402'               | 'NFND'    
 'CL1003511A'    | '1.6KOHM'    | '0.5%'       = 'SMC_0402R'          | '(SMC_0402R_C)'                        | 'RESISTOR, SINGLE, 1.6KOHM, THICK FILM, 0.5%, 50V, .063W, -55/125C, 0402'               | 'NFND'    
 'CL1003512A'    | '3.88KOHM'   | '0.5%'       = 'SMC_0402R'          | '(SMC_0402R_C)'                        | 'RESISTOR, SINGLE, 3.88KOHM, THICK FILM, 0.5%, 50V, .063W, -55/125C, 0402'              | 'NFND'    
 'CL1003513A'    | '5.9KOHM'    | '0.5%'       = 'SMC_0402R'          | '(SMC_0402R_C)'                        | 'RESISTOR, SINGLE, 5.9KOHM, THICK FILM, 0.5%, 50V, .063W, -55/125C, 0402'               | 'NFND'    
 'CL1003514A'    | '1.93KOHM'   | '0.5%'       = 'SMC_0603R'          | '(SMC_0603R)'                          | 'RESISTOR, SINGLE, 1.93KOHM, THIN FILM, 0.5%, 50V, .063W, -55/125C, 0603'               | 'NFND'    
 'CL1003515A'    | '2.1KOHM'    | '0.5%'       = 'SMC_0603R'          | '(SMC_0603R)'                          | 'RESISTOR, SINGLE, 2.1KOHM, THIN FILM, 0.5%, 50V, .063W, -55/125C, 0603'                | 'NFND'    
 'CL1003517A'    | '33OHM'      | '0.5%'       = 'SMC_0402R'          | '(SMC_0402R_C)'                        | 'RESISTOR, SINGLE, 33OHM, THICK FILM, .5%, 50V, .063W, -55/125C, 0402'                  | 'NFND'    
 'CL1003518A'    | '47OHM'      | '0.5%'       = 'SMC_0402R'          | '(SMC_0402R_C)'                        | 'RESISTOR, SINGLE, 47OHM, THICK FILM, .5%, 50V, .063W, -55/125C, 0402'                  | 'NFND'    
 'CL1003519A'    | '976OHM'     | '0.5%'       = 'SMC_0402R'          | '(SMC_0402R_C)'                        | 'RESISTOR, SINGLE, 976OHM, THICK FILM, .5%, 50V, .063W, -55/125C, 0402'                 | 'NFND'    
 'CL1003520A'    | '2.32KOHM'   | '0.5%'       = 'SMC_0402R'          | '(SMC_0402R_C)'                        | 'RESISTOR, SINGLE, 2.32KOHM, THICK FILM, .5%, 50V, .063W, -55/125C, 0402'               | 'NFND'    
 'CL1003521A'    | '619OHM'     | '0.5%'       = 'SMC_0402R'          | '(SMC_0402R_C)'                        | 'RESISTOR, SINGLE, 619OHM, THICK FILM, .5%, 50V, .063W, -55/125C, 0402'                 | 'NFND'    
 'CL1003522A'    | '432OHM'     | '0.5%'       = 'SMC_0402R'          | '(SMC_0402R_C)'                        | 'RESISTOR, SINGLE, 432OHM, THICK FILM, .5%, 50V, .063W, -55/125C, 0402'                 | 'NFND'    
 'CL1003523A'    | '267OHM'     | '0.5%'       = 'SMC_0402R'          | '(SMC_0402R_C)'                        | 'RESISTOR, SINGLE, 267OHM, THICK FILM, .5%, 50V, .063W, -55/125C, 0402'                 | 'NFND'    
 'CL1003524A'    | '1.3KOHM'    | '0.5%'       = 'SMC_0402R'          | '(SMC_0402R_C)'                        | 'RESISTOR, SINGLE, 1.3KOHM, THICK FILM, .5%, 50V, .063W, -55/125C, 0402'                | 'NFND'    
 'CL1003525A'    | '2.1KOHM'    | '0.5%'       = 'SMC_0402R'          | '(SMC_0402R_C)'                        | 'RESISTOR, SINGLE, 2.1KOHM, THICK FILM, .5%, 50V, .063W, -55/125C, 0402'                | 'NFND'    
 'CL1003526A'    | '2.87KOHM'   | '0.5%'       = 'SMC_0402R'          | '(SMC_0402R_C)'                        | 'RESISTOR, SINGLE, 2.87KOHM, THICK FILM, .5%, 50V, .063W, -55/125C, 0402'               | 'NFND'    
 'CL1003527A'    | '1.93KOHM'   | '0.5%'       = 'SMC_0402R'          | '(SMC_0402R_C)'                        | 'RESISTOR, SINGLE, 1.93KOHM, THICK FILM, .5%, 50V, .063W, -55/125C, 0402'               | 'NFND'    
 'CL1001401A'    | '10MOHM'     | '1%'         = 'SMC_0402R'          | '(SMC_0402R_C)'                        | 'RESISTOR, SINGLE, 10MOHM, THICK FILM, 1%, 50V, .063W, -55/125C, 0402'                  | 'NFND'    
 'CL1001402A'    | '499OHM'     | '1%'         = 'SMC_0402R'          | '(SMC_0402R_C)'                        | 'RESISTOR, SINGLE, 499OHM, THICK FILM, 1%, 50V, .063W, -55/125C, 0402'                  | 'NFND'    
 'CL1001403A'    | '19.1KOHM'   | '1%'         = 'SMC_0402R'          | '(SMC_0402R_C)'                        | 'RESISTOR, SINGLE, 19.1KOHM, THICK FILM, 1%, 50V, .063W, -55/125C, 0402'                | 'NFND'    
 'CL1001404A'    | '20KOHM'     | '1%'         = 'SMC_0402R'          | '(SMC_0402R_C)'                        | 'RESISTOR, SINGLE, 20KOHM, THICK FILM, 1%, 50V, .063W, -55/125C, 0402'                  | 'NFND'    
 'G152-00041-01' | '20KOHM'     | '1%'         = 'SMC_0402R'          | '(SMC_0402R_C)'                        | 'RESISTOR, SINGLE, 20KOHM, THICK FILM, 1%, 50V, .063W, -55/125C, 0402'                  | ''        
 'CL1001405A'    | '3.74KOHM'   | '1%'         = 'SMC_0402R'          | '(SMC_0402R_C)'                        | 'RESISTOR, SINGLE, 3.74KOHM, THICK FILM, 1%, 50V, .063W, -55/125C, 0402'                | 'NFND'    
 'CL1001406A'    | '510OHM'     | '1%'         = 'SMC_0402R'          | '(SMC_0402R_C)'                        | 'RESISTOR, SINGLE, 510OHM, THICK FILM, 1%, 50V, .063W, -55/125C, 0402'                  | 'NFND'    
 'CL1001407A'    | '300OHM'     | '1%'         = 'SMC_0402R'          | '(SMC_0402R_C)'                        | 'RESISTOR, SINGLE, 300OHM, THICK FILM, 1%, 50V, .063W, -55/125C, 0402'                  | 'NFND'    
 'G152-00035-01' | '300OHM'     | '1%'         = 'SMC_0402R'          | '(SMC_0402R_C)'                        | 'RESISTOR, SINGLE, 300OHM, THICK FILM, 1%, 50V, .063W, -55/125C, 0402'                  | ''        
 'CL1001408A'    | '4.7KOHM'    | '1%'         = 'SMC_0402R'          | '(SMC_0402R_C)'                        | 'RESISTOR, SINGLE, 4.7KOHM, THICK FILM, 1%, 50V, .063W, -55/125C, 0402'                 | 'NFND'    
 'G152-00042-01' | '4.7KOHM'    | '1%'         = 'SMC_0402R'          | '(SMC_0402R_C)'                        | 'RESISTOR, SINGLE, 4.7KOHM, THICK FILM, 1%, 50V, .063W, -55/125C, 0402'                 | 'NFND'    
 'CL1001409A'    | '8.2KOHM'    | '1%'         = 'SMC_0402R'          | '(SMC_0402R_C)'                        | 'RESISTOR, SINGLE, 8.2KOHM, THICK FILM, 1%, 50V, .063W, -55/125C, 0402'                 | 'NFND'    
 'CL1001410A'    | '10KOHM'     | '1%'         = 'SMC_0402R'          | '(SMC_0402R_C)'                        | 'RESISTOR, SINGLE, 10KOHM, THICK FILM, 1%, 50V, .063W, -55/125C, 0402'                  | 'NFND'    
 'G152-00034-01' | '10KOHM'     | '1%'         = 'SMC_0402R'          | '(SMC_0402R_C)'                        | 'RESISTOR, SINGLE, 10KOHM, THICK FILM, 1%, 50V, .063W, -55/125C, 0402'                  | 'NFND'    
 'CL1001412A'    | '62KOHM'     | '1%'         = 'SMC_0402R'          | '(SMC_0402R_C)'                        | 'RESISTOR, SINGLE, 62KOHM, THICK FILM, 1%, 50V, .063W, -55/125C, 0402'                  | 'NFND'    
 'CL1001413A'    | '280KOHM'    | '1%'         = 'SMC_0402R'          | '(SMC_0402R_C)'                        | 'RESISTOR, SINGLE, 280KOHM, THICK FILM, 1%, 50V, .063W, -55/125C, 0402'                 | 'NFND'    
 'CL1001414A'    | '124KOHM'    | '1%'         = 'SMC_0402R'          | '(SMC_0402R_C)'                        | 'RESISTOR, SINGLE, 124KOHM, THICK FILM, 1%, 50V, .063W, -55/125C, 0402'                 | 'NFND'    
 'CL1003539A'    | '.001OHM'    | '1%'         = 'SMC_R_250X125'      | '(SMC_R_250X125)'                      | 'RESISTOR, 1MOHM, 1%, 2W, -65/155C, 150PPM'                                             | 'NFND'    
 'CL1003540A'    | '475KOHM'    | '1%'         = 'SMC_1210R'          | '(SMC_1210R)'                          | 'RESISTOR, SINGLE, 475KOHM, THICK FILM, 1%, 200V, .33W, -55/155C, 1210'                 | 'NFND'    
 'CL1003541A'    | '7.5KOHM'    | '1%'         = 'SMC_1210R'          | '(SMC_1210R)'                          | 'RESISTOR, SINGLE, 7.5KOHM, THICK FILM, 1%, 200V, .33W, -55/155C, 1210'                 | 'NFND'    
 'CL1003542A'    | '1MOHM'      | '1%'         = 'SMC_1210R'          | '(SMC_1210R)'                          | 'RESISTOR, SINGLE, 1MOHM, THICK FILM, 1%, 200V, .33W, -55/155C, 1210'                   | 'NFND'    
 'CL1003543A'    | '34.8KOHM'   | '1%'         = 'SMC_1210R'          | '(SMC_1210R)'                          | 'RESISTOR, SINGLE, 34.8KOHM, THICK FILM, 1%, 200V, .33W, -55/155C, 1210'                | 'NFND'    
 'CL1003544A'    | '100KOHM'    | '1%'         = 'SMC_1210R'          | '(SMC_1210R)'                          | 'RESISTOR, SINGLE, 100KOHM, THICK FILM, 1%, 200V, .33W, -55/155C, 1210'                 | 'NFND'    
 'CL1003545A'    | '10KOHM'     | '1%'         = 'SMC_1210R'          | '(SMC_1210R)'                          | 'RESISTOR, SINGLE, 10KOHM, THICK FILM, 1%, 200V, .33W, -55/155C, 1210'                  | 'NFND'    
 'CL1003546A'    | '300KOHM'    | '1%'         = 'SMC_1210R'          | '(SMC_1210R)'                          | 'RESISTOR, SINGLE, 300KOHM, THICK FILM, 1%, 200V, .33W, -55/155C, 1210'                 | 'NFND'    
 'CL1003547A'    | '200KOHM'    | '1%'         = 'SMC_1210R'          | '(SMC_1210R)'                          | 'RESISTOR, SINGLE, 200KOHM, THICK FILM, 1%, 200V, .33W, -55/155C, 1210'                 | 'NFND'    
 'CL1003548A'    | '4.99KOHM'   | '1%'         = 'SMC_1210R'          | '(SMC_1210R)'                          | 'RESISTOR, SINGLE, 4.99KOHM, THICK FILM, 1%, 200V, .33W, -55/155C, 1210'                | 'NFND'    
 'CL1003549A'    | '3.92KOHM'   | '1%'         = 'SMC_1210R'          | '(SMC_1210R)'                          | 'RESISTOR, SINGLE, 3.92KOHM, THICK FILM, 1%, 200V, .33W, -55/155C, 1210'                | 'NFND'    
 'CL1003550A'    | '634OHM'     | '0.5%'       = 'SMC_0603R'          | '(SMC_0603R)'                          | 'RESISTOR, SINGLE, 634OHM, THICK FILM, 1%, 50V, .1W, -55/155C, 0603'                    | 'NFND'    
 'CL1003552A'    | '20KOHM'     | '5%'         = 'SMC_2512R'          | '(SMC_2512R)'                          | 'RESISTOR, SINGLE, 20KOHM, THICK FILM, 5%, 200V, 1W, -55/155C, 2512'                    | 'NFND'    
 'CL1003553A'    | '10KOHM'     | '5%'         = 'SMC_2512R'          | '(SMC_2512R)'                          | 'RESISTOR, SINGLE, 10KOHM, THICK FILM, 5%, 200V, 1W, -55/155C, 2512'                    | 'NFND'    
 'CL1003554A'    | '39.2KOHM'   | '1%'         = 'SMC_0603R'          | '(SMC_0603R)'                          | 'RESISTOR, SINGLE, 39.2KOHM, THICK FILM, 1%, 50V, .1W, -55/155C, 0603'                  | 'NFND'    
 'CL1003555A'    | '36.5KOHM'   | '1%'         = 'SMC_0603R'          | '(SMC_0603R)'                          | 'RESISTOR, SINGLE, 36.5KOHM, THICK FILM, 1%, 50V, .1W, -55/155C, 0603'                  | 'NFND'    
 'CL1003556A'    | '30KOHM'     | '1%'         = 'SMC_2010R'          | '(SMC_2010R)'                          | 'RESISTOR, SINGLE, 30KOHM, THICK FILM, 1%, 200V, .75W, -55/155C, 2010'                  | 'NFND'    
 'CL1003558A'    | '0.02OHM'    | '1%'         = 'SMC_1206R'          | '(SMC_1206R)'                          | 'RESISTOR, SINGLE, 0.02OHM, THICK FILM, 1%, .5W, -55/125C, 1206'                        | 'NFND'    
 'G152-00056-01' | '0.02OHM'    | '1%'         = 'SMC_1206R'          | '(SMC_1206R)'                          | 'RESISTOR, SINGLE, 0.02OHM, THICK FILM, 1%, .5W, -55/125C, 1206'                        | ''        
 'CL1003559A'    | '0.03OHM'    | '1%'         = 'SMC_1206R'          | '(SMC_1206R)'                          | 'RESISTOR, SINGLE, 0.03OHM, THICK FILM, 1%, .5W, -55/125C, 1206'                        | 'NFND'    
 'CL1003561A'    | '0.004OHM'   | '1%'         = 'SMC_R_196X098'      | '(SMC_R_196X098)'                      | 'RESISTOR, 4MOHM, 1%, 1W, -65/155C'                                                     | 'NFND'    
 'CL1003563A'    | '383OHM'     | '0.5%'       = 'SMC_0402R'          | '(SMC_0402R_C)'                        | 'RESISTOR, SINGLE, 383OHM, THICK FILM, 0.5%, 50V, .063W, -55/125C, 0402'                | 'NFND'    
 'CL1003564A'    | '3.92KOHM'   | '0.5%'       = 'SMC_0402R'          | '(SMC_0402R_C)'                        | 'RESISTOR, SINGLE, 3.92KOHM, THICK FILM, 0.5%, 50V, .063W, -55/125C, 0402'              | 'NFND'    
 'CL1003565A'    | '15OHM'      | '1%'         = 'SMC_1206R'          | '(SMC_1206R)'                          | 'RESISTOR, SINGLE, 15OHM, THICK FILM, 1%, 200V, .33W, -55/125C, 1206'                   | 'NFND'    
 'CL1003574A'    | '4.02KOHM'   | '1%'         = 'SMC_0402R'          | '(SMC_0402R_C)'                        | 'RESISTOR, SINGLE, 4.02KOHM, THICK FILM, 1%, 50V, .063W, -55/125C, 0402'                | ''        
 'CL1003575A'    | '432OHM'     | '1%'         = 'SMC_0603R'          | '(SMC_0603R)'                          | 'RESISTOR, SINGLE, 432OHM, THICK FILM, 1%, 50V, .1W, -55/125C, 0603'                    | 'NFND'    
 'CL1003576A'    | '976OHM'     | '1%'         = 'SMC_0603R'          | '(SMC_0603R)'                          | 'RESISTOR, SINGLE, 976OHM, THICK FILM, 1%, 50V, .1W, -55/125C, 0603'                    | 'NFND'    
 'CL1003577A'    | '80.6OHM'    | '1%'         = 'SMC_0402R'          | '(SMC_0402R_C)'                        | 'RESISTOR, SINGLE, 80.6OHM, THICK FILM, 1%, 50V, .063W, -55/125C, 0402'                 | 'NFND'    
 'CL1003579A'    | '60.4OHM'    | '1%'         = 'SMC_0603R'          | '(SMC_0603R)'                          | 'RESISTOR, SINGLE, 60.4OHM, THICK FILM, 1%, 50V, .1W, -55/125C, 0603'                   | 'NFND'    
 'CL1003580A'    | '0.051OHM'   | '1%'         = 'SMC_1206R'          | '(SMC_1206R)'                          | 'RESISTOR, SINGLE, 0.051OHM, THICK FILM, 1%, .5W, -55/125C, 1206'                       | 'NFND'    
 'CL1003581A'    | '0.039OHM'   | '1%'         = 'SMC_1206R'          | '(SMC_1206R)'                          | 'RESISTOR, SINGLE, 0.039OHM, THICK FILM, 1%, .5W, -55/125C, 1206'                       | 'NFND'    
 'CL1003582A'    | '2.87KOHM'   | '1%'         = 'SMC_2512R'          | '(SMC_2512R)'                          | 'RESISTOR, SINGLE, 2.87KOHM, THICK FILM, 1%, 200V, 1W, -55/125C, 2512'                  | 'NFND'    
 'CL1003583A'    | '3.9KOHM'    | '1%'         = 'SMC_2512R'          | '(SMC_2512R)'                          | 'RESISTOR, SINGLE, 3.9KOHM, THICK FILM, 1%, 200V, 1W, -55/125C, 2512'                   | 'NFND'    
 'CL1003587A'    | '130KOHM'    | '1%'         = 'SMC_0402R'          | '(SMC_0402R_C)'                        | 'RESISTOR, SINGLE, 130KOHM, THICK FILM, 1%, 50V, .063W, -55/125C, 0402'                 | 'NFND'    
 'CL1003597A'    | '1.62KOHM'   | '0.5%'       = 'SMC_0402R'          | '(SMC_0402R_C)'                        | 'RESISTOR, SINGLE, 1.62KOHM, THICK FILM, 0.5%, 50V, .063W, -55/125C, 0402'              | 'NFND'    
 'CL1003595A'    | '44.2OHM'    | '1%'         = 'SMC_0402R'          | '(SMC_0402R_C)'                        | 'RESISTOR, SINGLE, 44.2OHM, THICK FILM, 1%, 50V, .063W, -55/125C, 0402'                 | 'NFND'    
 'CL1003567A'    | '12KOHM'     | '1%'         = 'SMC_0402R'          | '(SMC_0402R_C)'                        | 'RESISTOR, SINGLE, 12KOHM, THICK FILM, 1%, 50V, .063W, -55/125C, 0402'                  | 'NFND'    
 'CL1003598A'    | '1.5KOHM'    | '1%'         = 'SMC_0402R'          | '(SMC_0402R_C)'                        | 'RESISTOR, SINGLE, 1.5KOHM, THICK FILM, 1%, 50V, .063W, -55/125C, 0402'                 | 'NFND'    
 'G152-00017-01' | '1.5KOHM'    | '1%'         = 'SMC_0402R'          | '(SMC_0402R_C)'                        | 'RESISTOR, SINGLE, 1.5KOHM, THICK FILM, 1%, 50V, .063W, -55/125C, 0402'                 | ''        
 'CL1003599A'    | '3.3KOHM'    | '1%'         = 'SMC_0402R'          | '(SMC_0402R_C)'                        | 'RESISTOR, SINGLE, 3.3KOHM, THICK FILM, 1%, 50V, .063W, -55/125C, 0402'                 | 'NFND'    
 'CL1003600A'    | '38.3KOHM'   | '1%'         = 'SMC_0402R'          | '(SMC_0402R_C)'                        | 'RESISTOR, SINGLE, 38.3KOHM, THICK FILM, 1%, 50V, .063W, -55/125C, 0402'                | 'NFND'    
 'CL1003601A'    | '84.5KOHM'   | '1%'         = 'SMC_0402R'          | '(SMC_0402R_C)'                        | 'RESISTOR, SINGLE, 84.5KOHM, THICK FILM, 1%, 50V, .063W, -55/125C, 0402'                | 'NFND'    
 'CL1003602A'    | '8.06KOHM'   | '1%'         = 'SMC_0402R'          | '(SMC_0402R_C)'                        | 'RESISTOR, SINGLE, 8.06KOHM, THICK FILM, 1%, 50V, .063W, -55/125C, 0402'                | 'NFND'    
 'G155-08061-01' | '8.06KOHM'   | '1%'         = 'SMC_0402R'          | '(SMC_0402R_C)'                        | 'RESISTOR, SINGLE, 8.06KOHM, THICK FILM, 1%, 50V, .063W, -55/125C, 0402'                | ''        
 'CL1003604A'    | '10MOHM'     | '1%'         = 'SMC_2010R'          | '(SMC_2010R)'                          | 'RESISTOR, SINGLE, 10MOHM, THICK FILM FOR HIGH VOLTAGE, 1%, 2000V, .5W, -55/125C, 2010' | 'NFND'    
 'CL1003608A'    | '22KOHM'     | '1%'         = ''                   | '()'                                   | 'RESISTOR, 22KOHM, 1%, 500V, 2W, -55/180C, 11.5*7MM'                                    | 'NFND'    
 'CL1003605A'    | '17.4KOHM'   | '1%'         = 'SMC_0402R'          | '(SMC_0402R_C)'                        | 'RESISTOR, SINGLE, 17.4KOHM, THICK FILM, 1%, 50V, .063W, -55/125C, 0402'                | 'NFND'    
 'CL1003607A'    | '120OHM'     | '1%'         = 'SMC_0402R'          | '(SMC_0402R_C)'                        | 'RESISTOR, SINGLE, 120OHM, THICK FILM, 1%, 50V, .063W, -55/125C, 0402'                  | 'NFND'    
 'CL1003612A'    | '437OHM'     | '1%'         = 'SMC_0402R'          | '(SMC_0402R_C)'                        | 'RESISTOR, SINGLE, 437OHM, THICK FILM, 1%, 25V, .063W, -55/125C, 0402'                  | 'NFND'    
 'CL1003613A'    | '2.91KOHM'   | '1%'         = 'SMC_0402R'          | '(SMC_0402R_C)'                        | 'RESISTOR, SINGLE, 2.91KOHM, THICK FILM, 1%, 25V, .063W, -55/125C, 0402'                | 'NFND'    
 'CL1003614A'    | '9.09KOHM'   | '1%'         = 'SMC_0402R'          | '(SMC_0402R_C)'                        | 'RESISTOR, SINGLE, 9.09KOHM, THICK FILM, 1%, 50V, .063W, -55/125C, 0402'                | 'NFND'    
 'CL1003615A'    | '3.57KOHM'   | '1%'         = 'SMC_0402R'          | '(SMC_0402R_C)'                        | 'RESISTOR, SINGLE, 3.57KOHM, THICK FILM, 1%, 50V, .063W, -55/125C, 0402'                | 'NFND'    
 'CL1003616A'    | '1.69KOHM'   | '1%'         = 'SMC_0402R'          | '(SMC_0402R_C)'                        | 'RESISTOR, SINGLE, 1.69KOHM, THICK FILM, 1%, 50V, .063W, -55/125C, 0402'                | 'NFND'    
 'CL1003618A'    | '2.94KOHM'   | '1%'         = 'SMC_2512R'          | '(SMC_2512R)'                          | 'RESISTOR, SINGLE, 2.94KOHM, THICK FILM, 1%, 200V, 1W, -55/125C, 2512'                  | 'NFND'    
 'CL1003619A'    | '3.92KOHM'   | '1%'         = 'SMC_0402R'          | '(SMC_0402R_C)'                        | 'RESISTOR, SINGLE, 3.92KOHM, THICK FILM, 1%, 50V, 0.063W, -55/125C, 0402'               | 'NFND'    
 'CL1003620A'    | '110KOHM'    | '1%'         = 'SMC_0805R'          | '(SMC_0805R)'                          | 'RESISTOR, SINGLE, 110KOHM, THICK FILM, 1%, 50V, .125W, -55/125C, 0805'                 | 'NFND'    
 'CL1003621A'    | '261OHM'     | '1%'         = 'SMC_0805R'          | '(SMC_0805R)'                          | 'RESISTOR, SINGLE, 261OHM, THICK FILM, 1%, 50V, .125W, -55/125C, 0805'                  | 'NFND'    
 'CL1003622A'    | '12.4KOHM'   | '1%'         = 'SMC_0805R'          | '(SMC_0805R)'                          | 'RESISTOR, SINGLE, 12.4KOHM, THICK FILM, 1%, 50V, .125W, -55/125C, 0805'                | 'NFND'    
 'CL1003623A'    | '10OHM'      | '1%'         = 'SMC_0805R'          | '(SMC_0805R)'                          | 'RESISTOR, SINGLE, 10OHM, THICK FILM, 1%, 50V, .125W, -55/125C, 0805'                   | 'NFND'    
 'CL1003624A'    | '499OHM'     | '1%'         = 'SMC_0805R'          | '(SMC_0805R)'                          | 'RESISTOR, SINGLE, 499OHM, THICK FILM, 1%, 50V, .125W, -55/125C, 0805'                  | 'NFND'    
 'CL1003625A'    | '180KOHM'    | '1%'         = 'SMC_0805R'          | '(SMC_0805R)'                          | 'RESISTOR, SINGLE, 180KOHM, THICK FILM, 1%, 50V, .125W, -55/125C, 0805'                 | 'NFND'    
 'CL1003626A'    | '45.3KOHM'   | '1%'         = 'SMC_0805R'          | '(SMC_0805R)'                          | 'RESISTOR, SINGLE, 45.3KOHM, THICK FILM, 1%, 50V, .125W, -55/125C, 0805'                | 'NFND'    
 'CL1003627A'    | '53.6KOHM'   | '1%'         = 'SMC_0805R'          | '(SMC_0805R)'                          | 'RESISTOR, SINGLE, 53.6KOHM, THICK FILM, 1%, 50V, .125W, -55/125C, 0805'                | 'NFND'    
 'CL1003628A'    | '412KOHM'    | '1%'         = 'SMC_0805R'          | '(SMC_0805R)'                          | 'RESISTOR, SINGLE, 412KOHM, THICK FILM, 1%, 50V, .125W, -55/125C, 0805'                 | 'NFND'    
 'CL1003629A'    | '14KOHM'     | '1%'         = 'SMC_0805R'          | '(SMC_0805R)'                          | 'RESISTOR, SINGLE, 14KOHM, THICK FILM, 1%, 50V, .125W, -55/125C, 0805'                  | 'NFND'    
 'CL1003630A'    | '39.2KOHM'   | '1%'         = 'SMC_0805R'          | '(SMC_0805R)'                          | 'RESISTOR, SINGLE, 39.2KOHM, THICK FILM, 1%, 50V, .125W, -55/125C, 0805'                | 'NFND'    
 'CL1003631A'    | '27KOHM'     | '1%'         = 'SMC_0805R'          | '(SMC_0805R)'                          | 'RESISTOR, SINGLE, 27KOHM, THICK FILM, 1%, 50V, .125W, -55/125C, 0805'                  | 'NFND'    
 'CL1003633A'    | '22KOHM'     | '1%'         = 'SMC_0402R'          | '(SMC_0402R_C)'                        | 'RESISTOR, SINGLE, 22KOHM, THICK FILM, 1%, .063W, -55/125C, 0402'                       | 'NFND'    
 'G155-02202-01' | '22KOHM'     | '1%'         = 'SMC_0402R'          | '(SMC_0402R_C)'                        | 'RESISTOR, SINGLE, 22KOHM, THICK FILM, 1%, .063W, -55/125C, 0402'                       | ''        
 'CL1003634A'    | '22.1KOHM'   | '1%'         = 'SMC_0402R'          | '(SMC_0402R_C)'                        | 'RESISTOR, SINGLE, 22.1KOHM, THICK FILM, 1%, 50V, .063W, -55/125C, 0402'                | 'NFND'    
 'CL1003637A'    | '5.49KOHM'   | '1%'         = 'SMC_0402R'          | '(SMC_0402R_C)'                        | 'RESISTOR, SINGLE, 5.49KOHM, THICK FILM, 1%, 50V, .063W, -55/125C, 0402'                | 'NFND'    
 'CL1003638A'    | '9.76KOHM'   | '1%'         = 'SMC_0402R'          | '(SMC_0402R_C)'                        | 'RESISTOR, SINGLE, 9.76KOHM, THICK FILM, 1%, 50V, .063W, -55/125C, 0402'                | 'NFND'    
 'CL1003639A'    | '6.65KOHM'   | '1%'         = 'SMC_0402R'          | '(SMC_0402R_C)'                        | 'RESISTOR, SINGLE, 6.65KOHM, THICK FILM, 1%, 50V, .063W, -55/125C, 0402'                | 'NFND'    
 'G152-00019-01' | '6.65KOHM'   | '1%'         = 'SMC_0402R'          | '(SMC_0402R_C)'                        | 'RESISTOR, SINGLE, 6.65KOHM, THICK FILM, 1%, 50V, .063W, -55/125C, 0402'                | ''        
 'CL1003640A'    | '54.9KOHM'   | '0.1%'       = 'SMC_0603R'          | '(SMC_0603R)'                          | 'RESISTOR, SINGLE, 54.9KOHM, METAL FILM, 0.1%, 50V, .063W, 0603'                        | 'NFND'    
 'CL1003641A'    | '10KOHM'     | '0.1%'       = 'SMC_0603R'          | '(SMC_0603R)'                          | 'RESISTOR, SINGLE, 10KOHM, METAL FILM, 0.1%, 50V, .063W, 0603'                          | 'NFND'    
 'CL1003642A'    | '53.6KOHM'   | '0.1%'       = 'SMC_0603R'          | '(SMC_0603R)'                          | 'RESISTOR, SINGLE, 53.6KOHM, METAL FILM, 0.1%, 50V, .063W, 0603'                        | 'NFND'    
 'CL1003643A'    | '54.9OHM'    | '1%'         = 'SMC_0402R'          | '(SMC_0402R_C)'                        | 'RESISTOR, SINGLE, 54.9OHM, THICK FILM, 1%, 50V, .063W, -55/125C, 0402'                 | 'NFND'    
 'CL1003644A'    | '220KOHM'    | '1%'         = 'SMC_1210R'          | '(SMC_1210R)'                          | 'RESISTOR, SINGLE, 220KOHM, THICK FILM, 1%, 200V, .33W, -55/125C, 1210'                 | 'NFND'    
 'CL1003647A'    | '1.33KOHM'   | '0.1%'       = 'SMC_0603R'          | '(SMC_0603R)'                          | 'RESISTOR, SINGLE, 1.33KOHM, METAL FILM, 0.1%, 0.063W, 0603'                            | 'NFND'    
 'CL1003648A'    | '417OHM'     | '0.1%'       = 'SMC_0603R'          | '(SMC_0603R)'                          | 'RESISTOR, SINGLE, 417OHM, METAL FILM, 0.1%, 0.063W, 0603'                              | 'NFND'    
 'CL1003649A'    | '142OHM'     | '0.1%'       = 'SMC_0603R'          | '(SMC_0603R)'                          | 'RESISTOR, SINGLE, 142OHM, METAL FILM, 0.1%, 0.063W, 0603'                              | 'NFND'    
 'CL1003651A'    | '412OHM'     | '1%'         = 'SMC_0603R'          | '(SMC_0603R)'                          | 'RESISTOR, SINGLE, 412OHM, THICK FILM, 1%, .1W, 0603'                                   | 'NFND'    
 'CL1003652A'    | '143OHM'     | '1%'         = 'SMC_0603R'          | '(SMC_0603R)'                          | 'RESISTOR, SINGLE, 143OHM, THICK FILM, 1%, .1W, 0603'                                   | 'NFND'    
 'CL1003653A'    | '53.6KOHM'   | '1%'         = 'SMC_0603R'          | '(SMC_0603R)'                          | 'RESISTOR, SINGLE, 53.6KOHM, THICK FILM, 1%, .1W, 0603'                                 | 'NFND'    
 'CL1003654A'    | '1.33KOHM'   | '1%'         = 'SMC_0603R'          | '(SMC_0603R)'                          | 'RESISTOR, SINGLE, 1.33KOHM, THICK FILM, 1%, .1W, 0603'                                 | 'NFND'    
 'CL1003660A'    | '1.8MOHM'    | '1%'         = 'SMC_0603R'          | '(SMC_0603R)'                          | 'RESISTOR, SINGLE, 1.8MOHM, THICK FILM, 1%, 50V, .1W, -55/125C, 0603'                   | 'NFND'    
 'CL1003661A'    | '2.2KOHM'    | '1%'         = 'SMC_0603R'          | '(SMC_0603R)'                          | 'RESISTOR, SINGLE, 2.2KOHM, THICK FILM, 1%, 50V, .1W, -55/125C, 0603'                   | 'NFND'    
 'CL1003662A'    | '15KOHM'     | '1%'         = 'SMC_0603R'          | '(SMC_0603R)'                          | 'RESISTOR, SINGLE, 15KOHM, THICK FILM, 1%, 50V, .1W, -55/125C, 0603'                    | 'NFND'    
 'G152-00021-01' | '15KOHM'     | '1%'         = 'SMC_0603R'          | '(SMC_0603R)'                          | 'RESISTOR, SINGLE, 15KOHM, THICK FILM, 1%, 50V, .1W, -55/125C, 0603'                    | ''        
 'CL1003663A'    | '2.7KOHM'    | '1%'         = 'SMC_0603R'          | '(SMC_0603R)'                          | 'RESISTOR, SINGLE, 2.7KOHM, THICK FILM, 1%, 50V, .1W, -55/125C, 0603'                   | 'NFND'    
 'CL1003664A'    | '2.2KOHM'    | '1%'         = 'SMC_0402R'          | '(SMC_0402R_C)'                        | 'RESISTOR, SINGLE, 2.2KOHM, THICK FILM, 1%, 50V, .063W, -55/125C, 0402'                 | 'NFND'    
 'CL1003665A'    | '15KOHM'     | '1%'         = 'SMC_0402R'          | '(SMC_0402R_C)'                        | 'RESISTOR, SINGLE, 15KOHM, THICK FILM, 1%, 50V, .063W, -55/125C, 0402'                  | 'NFND'    
 'G152-00018-01' | '15KOHM'     | '1%'         = 'SMC_0402R'          | '(SMC_0402R_C)'                        | 'RESISTOR, SINGLE, 15KOHM, THICK FILM, 1%, 50V, .063W, -55/125C, 0402'                  | ''        
 'CL1003666A'    | '2.7KOHM'    | '1%'         = 'SMC_0402R'          | '(SMC_0402R_C)'                        | 'RESISTOR, SINGLE, 2.7KOHM, THICK FILM, 1%, 50V, .063W, -55/125C, 0402'                 | 'NFND'    
 'CL1003670A'    | '56OHM'      | '1%'         = 'SMC_0402R'          | '(SMC_0402R_C)'                        | 'RESISTOR, SINGLE,56OHM, THICK FILM, 1%, 50V, .063W, -55/125C, 0402'                    | 'NFND'    
 'CL1003671A'    | '1.5MOHM'    | '1%'         = 'SMC_0402R'          | '(SMC_0402R_C)'                        | 'RESISTOR, SINGLE,1.5MOHM, THICK FILM, 1%, 50V, .063W, -55/125C, 0402'                  | 'NFND'    
 'CL1003672A'    | '3.9KOHM'    | '1%'         = 'SMC_0402R'          | '(SMC_0402R_C)'                        | 'RESISTOR, SINGLE, 3.9KOHM, THICK FILM, 1%, 50V, .063W, -55/125C, 0402'                 | 'NFND'    
 'CL1003673A'    | '180KOHM'    | '1%'         = 'SMC_0402R'          | '(SMC_0402R_C)'                        | 'RESISTOR, SINGLE, 180KOHM, THICK FILM, 1%, 50V, .063W, -55/125C, 0402'                 | 'NFND'    
 'CL1003674A'    | '3MOHM'      | '1%'         = 'SMC_0402R'          | '(SMC_0402R_C)'                        | 'RESISTOR, SINGLE, 3MOHM, THICK FILM, 1%, 50V, .063W, -55/125C, 0402'                   | 'NFND'    
 'CL1003675A'    | '20MOHM'     | '1%'         = 'SMC_0402R'          | '(SMC_0402R_C)'                        | 'RESISTOR, SINGLE, 20MOHM, THICK FILM, 1%, 50V, .063W, -55/125C, 0402'                  | 'NFND'    
 'CL1003676A'    | '1.07KOHM'   | '1%'         = 'SMC_1210R'          | '(SMC_1210R)'                          | 'RESISTOR, SINGLE, 1.07KOHM, THICK FILM, 1%, 200V, 1/2W, -55/125C, 1210'                | 'NFND'    
 'CL1003677A'    | '3.65KOHM'   | '1%'         = 'SMC_1210R'          | '(SMC_1210R)'                          | 'RESISTOR, SINGLE, 3.65KOHM, THICK FILM, 1%, 200V, 1/2W, -55/125C, 1210'                | 'NFND'    
 'CL1003678A'    | '2.49KOHM'   | '1%'         = 'SMC_1210R'          | '(SMC_1210R)'                          | 'RESISTOR, SINGLE, 2.49KOHM, THICK FILM, 1%, 200V, 1/2W, -55/125C, 1210'                | 'NFND'    
 'CL1003679A'    | '73.2OHM'    | '1%'         = 'SMC_1210R'          | '(SMC_1210R)'                          | 'RESISTOR, SINGLE, 73.2OHM, THICK FILM, 1%, 200V, 1/2W, -55/125C, 1210'                 | 'NFND'    
 'CL1003680A'    | '536OHM'     | '1%'         = 'SMC_0805R'          | '(SMC_0805R)'                          | 'RESISTOR, SINGLE, 536OHM, THICK FILM, 1%, 150V, 1/4W, -55/125C, 0805'                  | 'NFND'    
 'CL1003686A'    | '56.2KOHM'   | '1%'         = 'SMC_0402R'          | '(SMC_0402R_C)'                        | 'RESISTOR, SINGLE, 56.2KOHM, THICK FILM, 1%, 50V, .063W, -55/125C, 0402'                | 'NFND'    
 'CL1003687A'    | '0.22OHM'    | '1%'         = 'SMC_2512R'          | '(SMC_2512R)'                          | 'RESISTOR, SINGLE, 0.22OHM, 1%, 1W, -65/170C, 2512'                                     | 'NFND'    
 'CL1003688A'    | '0.5OHM'     | '1%'         = 'SMC_0603R'          | '(SMC_0603R)'                          | 'RESISTOR, SINGLE, 0.5OHM, 1%, .2W, 200PPM, 0603'                                       | 'NFND'    
 'G156-0R500-01' | '0.5OHM'     | '1%'         = 'SMC_0603R'          | '(SMC_0603R)'                          | 'RESISTOR, SINGLE, 0.5OHM, 1%, .2W, 200PPM, 0603'                                       | ''        
 'CL1003691A'    | '50OHM'      | '5%'         = 'SMC_2010R'          | '(SMC_2010R)'                          | 'RES, 50OHM, +/-5%, 0.5W, 2010'                                                         | 'NFND'    
 'CL1003693A'    | '56KOHM'     | '1%'         = 'SMC_0402R'          | '(SMC_0402R_C)'                        | 'RES, 56KOHM, 1%, .063W, 0402'                                                          | 'NFND'    
 'CL1003694A'    | '47KOHM'     | '1%'         = 'SMC_0402R'          | '(SMC_0402R_C)'                        | 'RES, 47KOHM, 1%, .063W, 50V, 0402'                                                     | 'NFND'    
 'CL1003706A'    | '47OHM'      | '1%'         = 'A2_R145_P625'       | '(A2_R145_P625)'                       | 'FUSIBLE, 47OHM, 1%, VRMS 500V'                                                         | 'NFND'    
 'CL1003708A'    | '200KOHM'    | '1%'         = 'SMC_0805R'          | '(SMC_0805R)'                          | 'RES, 200KOHM, 5%, 1/8W, 150V, 0805'                                                    | 'NFND'    
 'CL1003710A'    | '200OHM'     | '10%'        = 'SMC_2512R'          | '(SMC_2512R)'                          | 'RES, 200OHM, 10%, 1W, 200V, 2512'                                                      | 'NFND'    
 'CL1003711A'    | '8.06OHM'    | '0.5%'       = 'SMC_0805R'          | '(SMC_0805R)'                          | 'RES, 8.06OHM, 0.25W, +/-0.5%, 0805'                                                    | 'NFND'    
 'CL1003712A'    | '47OHM'      | '5%'         = 'SMC_R_374X138'      | '(SMC_R_374X138)'                      | 'RES,47OHM,0.5W,+/-5%'                                                                  | 'NFND'    
 'CL1003713A'    | '68OHM'      | '10%'        = 'SMC_2010R_H028'     | '(SMC_2010R_H028)'                     | 'RES, 68OHM, 10%, 0.75W, 200V, 2010'                                                    | 'NFND'    
 'CL1003714A'    | '390KOHM'    | '5%'         = 'SMC_1206R_H028'     | '(SMC_1206R_H028)'                     | 'RES, 390KOHM, 1/4W, 5%, 500V, 1206'                                                    | 'NFND'    
 'CL1003731A'    | '.20OHM'     | '1%'         = 'SMC_1206R_H028'     | '(SMC_1206R_H028)'                     | 'RES, .20OHM, 1/4W, 1%, 1206'                                                           | 'NFND'    
 'CL1003742A'    | '0.33OHM'    | '5%'         = 'A2_R094_P510'       | '(A2_R094_P510)'                       | 'RES, 0.33OHM, 1W, 5%, LEAD TYPE'                                                       | 'NFND'    
 'CL1003732A'    | '0.68OHM'    | '1%'         = 'SMC_2512R_H028'     | '(SMC_2512R_H028)'                     | 'RES, 0.68OHM, 1W, 1%, 2512'                                                            | 'NFND'    
 'CL1003733A'    | '0.68OHM'    | '1%'         = 'SMC_1210R_H028'     | '(SMC_1210R_H028)'                     | 'RES, 0.68OHM, 0.5W, 1%, 1210'                                                          | 'NFND'    
 'CL1003743A'    | '470OHM'     | '50%'        = 'SMC_0603R_H038'     | '(SMC_0603R_H038)'                     | 'RES, THERMISTOR, PTC, 470OHM, 50%, 85C, 0603, SMD'                                     | 'NFND'    
 'CL1003744A'    | '3.3KOHM'    | '3%'         = 'SMC_0603R_H038'     | '(SMC_0603R_H038)'                     | 'RES, THERMISTORS, NTC, 3.3KOHM, 3%, 0603, SMD'                                         | 'NFND'    
 'CL1003730A'    | '120OHM'     | '5%'         = 'A2_R098_P492'       | '(A2_R098_P318_CST)'                   | 'RES, 120OHM, 1W, 5%, LEAD TYPE'                                                        | 'NFND'    
 'CL1003746A'    | '380OHM'     | '1%'         = 'SMC_0603R_H022'     | '(SMC_0603R_H022)'                     | 'RES, 380OHM, 0.1W, 1%, 0603'                                                           | 'NFND'    
 'CL1003745A'    | '137OHM'     | '1%'         = 'SMC_0603R_H022'     | '(SMC_0603R_H022)'                     | 'RES, 137OHM, 0.1W, 1%, 0603'                                                           | 'NFND'    
 'CL1003734A'    | '5.6KOHM'    | '5%'         = 'SMC_0603R_H022'     | '(SMC_0603R_H022)'                     | 'RES, 5.6KOHM, 0.1W, 5%, 0603'                                                          | 'NFND'    
 'CL1003735A'    | '47KOHM'     | '5%'         = 'SMC_2512R_H028'     | '(SMC_2512R_H028)'                     | 'RES, 47KOHM, 1W, 5%, 2512'                                                             | 'NFND'    
 'CL1003736A'    | '6.2KOHM'    | '1%'         = 'SMC_0603R_H022'     | '(SMC_0603R_H022)'                     | 'RES, 6.2KOHM, 0.1W, 1%, 0603'                                                          | 'NFND'    
 'CL1003737A'    | '47KOHM'     | '1%'         = 'SMC_0603R_H022'     | '(SMC_0603R_H022)'                     | 'RES, 47KOHM, 0.1W, 1%, 0603'                                                           | 'NFND'    
 'CL1003738A'    | '22KOHM'     | '5%'         = 'SMC_1206R_H028'     | '(SMC_1206R_H028)'                     | 'RES, 22KOHM, 0.25W, 5%, 1206'                                                          | 'NFND'    
 'CL1003739A'    | '16KOHM'     | '1%'         = 'SMC_0603R_H022'     | '(SMC_0603R_H022)'                     | 'RES, 16KOHM, 0.1W, 1%, 0603'                                                           | 'NFND'    
 'CL1003740A'    | '24KOHM'     | '1%'         = 'SMC_0603R_H022'     | '(SMC_0603R_H022)'                     | 'RES, 24KOHM, 0.1W, 1%, 0603'                                                           | 'NFND'    
 'CL1003741A'    | '499KOHM'    | '1%'         = 'SMC_1206R_H028'     | '(SMC_1206R_H028)'                     | 'RES, 499KOHM, 0.25W, 1%, 1206'                                                         | 'NFND'    
 'CL1003760A'    | '44.2KOHM'   | '1%'         = 'SMC_1206R_H022'     | '(SMC_1206R_H022)'                     | 'RES, 44.2KOHM, 1%, 50V, .1W, -55/125C, 0603'                                           | 'NFND'    
 'CL1003761A'    | '576OHM'     | '1%'         = 'SMC_1206R_H022'     | '(SMC_1206R_H022)'                     | 'RES, 576OHM, 1%, 50V, .1W, -55/125C, 0603'                                             | 'NFND'    
 'CL1003762A'    | '22.1KOHM'   | '1%'         = 'SMC_1206R_H022'     | '(SMC_1206R_H022)'                     | 'RES, 22.1KOHM, 1%, 50V, .1W, -55/125C, 0603'                                           | 'NFND'    
 'CL100775A'     | '681KOHM'    | '1%'         = 'SMC_0402R_H016'     | '(SMC_0402R_H016)'                     | 'RESISTOR, SINGLE, 681KOHM, THICK FILM, 1%, 50V, .063W, -55/125C, 0402'                 | 'NFND'    
 'CL1003773A'    | '11.5KOHM'   | '1%'         = 'SMC_0402R_H016'     | '(SMC_0402R_H016)'                     | 'RESISTOR, SINGLE, 11.5KOHM, THICK FILM, 1%, 50V, .063W, -55/125C, 0402'                | 'NFND'    
 'CL1003772A'    | '39.2KOHM'   | '1%'         = 'SMC_0402R_H016'     | '(SMC_0402R_H016)'                     | 'RESISTOR, SINGLE, 39.2KOHM, THICK FILM, 1%, 50V, .063W, -55/125C, 0402'                | 'NFND'    
 'CL1003771A'    | '36.5KOHM'   | '1%'         = 'SMC_0402R_H016'     | '(SMC_0402R_H016)'                     | 'RESISTOR, SINGLE, 36.5KOHM, THICK FILM, 1%, 50V, .063W, -55/125C, 0402'                | 'NFND'    
 'CL1003774A'    | '6.98KOHM'   | '1%'         = 'SMC_0603R_H022'     | '(SMC_0603R_H022)'                     | 'RES, 6.98KOHM, 1%, 50V, .1W, -55/125C, 0603'                                           | 'NFND'    
 'CL1003775A'    | '470OHM'     | '50%'        = 'SMC_0603R_H038'     | '(SMC_0603R_H038)'                     | 'RES, THERMISTOR, PTC, 470OHM, 50%, 95C, 0603, SMD'                                     | 'NFND'    
 'CL1003776A'    | '191OHM'     | '1%'         = 'SMC_0603R_H022'     | '(SMC_0603R_H022)'                     | 'RESISTOR, SINGLE, 191OHM, THICK FILM, 1%, 50V, .1W, -55/125C, 0603'                    | 'NFND'    
 'CL1003782A'    | '10KOHM'     | '0.5%'       = 'SMC_0603R_H022'     | '(SMC_0603R_H022)'                     | 'RES, 10KOHM, 0.5%, 50V, 0.1W, -55/125C, 0603'                                          | 'NFND'    
 'CL1003781A'    | '75KOHM'     | '0.5%'       = 'SMC_0603R_H022'     | '(SMC_0603R_H022)'                     | 'RES, 75KOHM, 0.5%, 50V, 0.1W, -55/125C, 0603'                                          | 'NFND'    
 'CL1003780A'    | '470OHM'     | '0.5%'       = 'SMC_0603R_H022'     | '(SMC_0603R_H022)'                     | 'RES, 470OHM, 0.5%, 50V, 0.1W, -55/125C, 0603'                                          | 'NFND'    
 'CL1003779A'    | '1KOHM'      | '0.5%'       = 'SMC_0603R_H022'     | '(SMC_0603R_H022)'                     | 'RES, 1KOHM, 0.5%, 50V, 0.1W, -55/125C, 0603'                                           | 'NFND'    
 'CL1003778A'    | '820KOHM'    | '0.5%'       = 'SMC_0603R_H022'     | '(SMC_0603R_H022)'                     | 'RES, 820KOHM, 0.5%, 50V, 0.1W, -55/125C, 0603'                                         | 'NFND'    
 'CL1003777A'    | '300KOHM'    | '0.5%'       = 'SMC_0603R_H022'     | '(SMC_0603R_H022)'                     | 'RES, 300KOHM, 0.5%, 50V, 0.1W, -55/125C, 0603'                                         | 'NFND'    
 'CL1003789A'    | '649OHM'     | '1%'         = 'SMC_0402R_H016'     | '(SMC_0402R_H016)'                     | 'RES, 649OHM, 1%, 50V, 0.063W, -55/125C, 0402'                                          | 'NFND'    
 'CL1003795A'    | '240OHM'     | '1%'         = 'SMC_0603R_H022'     | '(SMC_0603R_H022)'                     | 'RES, 240OHM, 1%, 50V, .1W, -55/125C, 0603'                                             | 'NFND'    
 'G156-02400-01' | '240OHM'     | '1%'         = 'SMC_0603R_H022'     | '(SMC_0603R_H022)'                     | 'RES, 240OHM, 1%, 50V, .1W, -55/125C, 0603'                                             | ''        
 'CL1003796A'    | '36OHM'      | '1%'         = 'SMC_0603R_H022'     | '(SMC_0603R_H022)'                     | 'RES, 36OHM, 1%, 50V, .1W, -55/125C, 0603'                                              | 'NFND'    
 'CL1003797A'    | '499OHM'     | '1%'         = 'SMC_0603R_H022'     | '(SMC_0603R_H022)'                     | 'RES, 499OHM, 1%, 50V, .1W, -55/125C, 0603'                                             | 'NFND'    
 'CL1003798A'    | '0.02OHM'    | '1%'         = 'SMC_2512R_V1'       | '(SMC_2512R_V1)'                       | 'RES, 0.02OHM, 1%, 1W, -55/125C, 2512'                                                  | 'NFND'    
 'CL1003802A'    | '120OHM'     | '1%'         = 'SMC_2512R_H028'     | '(SMC_2512R_H028)'                     | 'RES, 120OHM, 1%, 200V, 1W, -55/125C, 2512'                                             | 'NFND'    
 'CL1003803A'    | '200KOHM'    | '1%'         = 'SMC_2512R_H028'     | '(SMC_2512R_H028)'                     | 'RES, 200KOHM, 1%, 200V, 1W, -55/125C, 2512'                                            | 'NFND'    
 'G152-10007-01' | '22OHM'      | '5%'         = 'SMC_0402R_H016'     | '(SMC_0402R_C_H016)'                   | 'RESISTOR,SINGLE,22OHM,THICK FILM,5%,50V,0.063W,0402'                                   | ''        
 'G152-10008-01' | '10KOHM'     | '5%'         = 'SMC_0402R_H016'     | '(SMC_0402R_C_H016)'                   | 'RESISTOR, SINGLE, 10KOHM, THICK FILM, 5%, 50V, 0.063W,0402 '                           | ''        
 'G152-10009-01' | '68OHM'      | '5%'         = 'SMC_0603R_H020'     | '(SMC_0603R_H020)'                     | 'RESISTOR, SINGLE,68OHM,THICK FILM,5%,50V,0.1W,0603'                                    | 'NFND'    
 'G152-10013-01' | '0OHM'       | '5%'         = 'SMC_0603R_H020'     | '(SMC_0603R_H020)'                     | 'RES, 0 OHMS, +/-5%, 0.1W, 0603, ROHS COMPLIANT'                                        | ''        
 'CL1003834A'    | '0.01OHM'    | '1%'         = 'SMC_2512R_H028'     | '(SMC_2512R_H028)'                     | 'RES, 0.01OHM, 1%, 1W, -55/125C, 2512'                                                  | 'NFND'    
 'G152-10017-01' | '150KOHM'    | '2%'         = 'SMC_R_1210'         | '(SMC_R_1210)'                         | 'RES,150KOHM, 0.33W, 2%, 1210'                                                          | 'NFND'    
 'G152-10016-01' | '0.40OHM'    | '1%'         = 'SMC_R_1210'         | '(SMC_R_1210)'                         | 'RES, 0.40OHM, .5W, 1%, 1210'                                                           | 'NFND'    
 'G152-10015-01' | '56OHM'      | '2%'         = 'SMC_R_1210'         | '(SMC_R_1210)'                         | 'RES, 56OHM, 0.5W, 2%, 1210'                                                            | 'NFND'    
 'G152-10014-01' | '100KOHM'    | '2%'         = 'SMC_R_1206'         | '(SMC_R_1206)'                         | 'RES, 100KOHM, 0.25W, 2%, 1206'                                                         | ''        
 'G152-10018-01' | '180OHM'     | '2%'         = 'SMC_R_1206'         | '(SMC_R_1206)'                         | 'RES, 180OHM, 0.25W, 2%, 1206'                                                          | 'NFND'    
 'G152-10020-01' | '180OHM'     | '1%'         = 'SMC_R_1206'         | '(SMC_R_1206)'                         | 'RES, 180OHM, 0.25W, 1%, 1206'                                                          | 'NFND'    
 'G152-10021-01' | '150KOHM'    | '1%'         = 'SMC_R_1210'         | '(SMC_R_1210)'                         | 'RES,150KOHM, 0.33W, 1%, 1210'                                                          | ''        
 'G152-10022-01' | '56OHM'      | '1%'         = 'SMC_R_1210'         | '(SMC_R_1210)'                         | 'RES, 56OHM, 0.5W, 1%, 1210'                                                            | ''        
 'G152-10023-01' | '4.7KOHM'    | '1%'         = 'SMC_R_1206'         | '(SMC_R_1206)'                         | 'RES, 4.7KOHM, 0.25W, 1%, 1206'                                                         | ''        
 'G152-10024-01' | '0.39OHM'    | '1%'         = 'SMC_R_1210'         | '(SMC_R_1210)'                         | 'RES, 0.39OHM, .5W, 1%, 1210'                                                           | 'NFND'    
 'G155-04751-01' | '4.75KOHM'   | '1%'         = 'SMC_0402R_H016'     | '(SMC_0402R_C_H016)'                   | 'RES,4.75K,1%,0.063W,0402'                                                              | ''        
 'G156-06492-01' | '64.9KOHM'   | '1%'         = 'SMC_0603R_H022'     | '(SMC_0603R_H022)'                     | 'RES,64.9K,1%,0.1W,0603'                                                                | ''        
 'G156-01402-01' | '14KOHM'     | '1%'         = 'SMC_0603R_H022'     | '(SMC_0603R_H022)'                     | 'RES,14.0K,1%,0.1W,0603'                                                                | 'NFND'    
 'G156-08561-01' | '8.56KOHM'   | '1%'         = 'SMC_0603R_H022'     | '(SMC_0603R_H022)'                     | 'RES,8.56K,1%,0.1W,0603'                                                                | ''        
 'G156-04122-01' | '41.2KOHM'   | '1%'         = 'SMC_0603R_H022'     | '(SMC_0603R_H022)'                     | 'RES,41.2K,1%,0.1W,0603'                                                                | ''        
 'G156-08761-01' | '8.76KOHM'   | '1%'         = 'SMC_0603R_H022'     | '(SMC_0603R_H022)'                     | 'RES,8.76K,1%,0.1W,0603'                                                                | ''        
 'G156-02342-01' | '23.4KOHM'   | '1%'         = 'SMC_0603R_H022'     | '(SMC_0603R_H022)'                     | 'RES,23.4K,1%,0.1W,0603'                                                                | ''        
 'G156-02522-01' | '25.2KOHM'   | '1%'         = 'SMC_0603R_H022'     | '(SMC_0603R_H022)'                     | 'RES,25.2K,1%,0.1W,0603'                                                                | ''        
 'G156-05362-01' | '53.6KOHM'   | '1%'         = 'SMC_0603R_H022'     | '(SMC_0603R_H022)'                     | 'RES,53.6K,1%,0.1W,0603'                                                                | ''        
 'G156-02153-01' | '215KOHM'    | '1%'         = 'SMC_0603R_H022'     | '(SMC_0603R_H022)'                     | 'RES,215K,1%,0.1W,0603'                                                                 | ''        
 'G156-06422-01' | '64.2KOHM'   | '1%'         = 'SMC_0603R_H022'     | '(SMC_0603R_H022)'                     | 'RES,64.2K,1%,0.1W,0603'                                                                | ''        
 'G156-06980-01' | '698OHM'     | '1%'         = 'SMC_0603R_H022'     | '(SMC_0603R_H022)'                     | 'RES,698,1%,0.1W,0603'                                                                  | ''        
 'G156-07680-01' | '768OHM'     | '1%'         = 'SMC_0603R_H022'     | '(SMC_0603R_H022)'                     | 'RES,768,1%,0.1W,0603'                                                                  | ''        
 'G156-01173-01' | '117KOHM'    | '1%'         = 'SMC_0603R_H022'     | '(SMC_0603R_H022)'                     | 'RES,117K,1%,0.1W,0603'                                                                 | ''        
 'G152-10080-01' | '0.002OHM'   | '1%'         = 'SMC_R_250X125_V1'   | '(SMC_R_250X125_V1)'                   | 'RES,0.002OHM,1%,2W,2512'                                                               | 'NFND'    
 'G156-05973-01' | '597KOHM'    | '1%'         = 'SMC_0603R_H022'     | '(SMC_0603R_H022)'                     | 'RES,597K,1%,0.1W,0603'                                                                 | 'OBSOLETE'
 'G156-00222-01' | '2.2KOHM'    | '1%'         = 'SMC_0603R_H022'     | '(SMC_0603R_H022)'                     | 'RES,2.2K,1%,0.1W,0603'                                                                 | ''        
 'G155-01201-01' | '1.2KOHM'    | '1%'         = 'SMC_0402R_H016'     | '(SMC_0402R_C_H016)'                   | 'RES,1.2K,1%,0.0625W,0402'                                                              | ''        
 'G156-0R499-01' | '0.499OHM'   | '1%'         = 'SMC_0603R_H024'     | '(SMC_0603R_H024)'                     | 'RES,0.499OHM,1%,0.2W,0603'                                                             | ''        
 'G156-018R2-01' | '18.2OHM'    | '1%'         = 'SMC_0603R_H022'     | '(SMC_0603R_H022)'                     | 'RES,18R2,1%,0.1W,0603'                                                                 | 'NFND'    
 'G155-03322-01' | '33.2KOHM'   | '1%'         = 'SMC_0402R_H016'     | '(SMC_0402R_C_H016)'                   | 'RES,33.2K,1%,0.063W,0402'                                                              | ''        
 'G156-01871-01' | '1.87KOHM'   | '1%'         = 'SMC_0603R_H022'     | '(SMC_0603R_H022)'                     | 'RES,1.87K,1%,0.1W,0603'                                                                | ''        
 'G156-03400-01' | '340OHM'     | '1%'         = 'SMC_0603R_H022'     | '(SMC_0603R_H022)'                     | 'RES,340,1%,0.1W,0603'                                                                  | ''        
 'G156-00221-05' | '220OHM'     | '5%'         = 'SMC_0603R_H022'     | '(SMC_0603R_H022)'                     | 'RES,220,5%,0.1W,0603'                                                                  | ''        
 'G156-00512-05' | '5.1KOHM'    | '5%'         = 'SMC_0603R_H022'     | '(SMC_0603R_H022)'                     | 'RES,5.1K,5%,0.1W,0603'                                                                 | ''        
 'G156-05231-01' | '5.23KOHM'   | '1%'         = 'SMC_0603R_H022'     | '(SMC_0603R_H022)'                     | 'RES,5.23K,1%,0.1W,0603'                                                                | ''        
 'G155-03401-01' | '3.40KOHM'   | '1%'         = 'SMC_0402R_H016'     | '(SMC_0402R_C_H016)'                   | 'RES,3.40K,1%,0.063W,0402'                                                              | ''        
 'G156-00822-05' | '8.2KOHM'    | '5%'         = 'SMC_0603R_H022'     | '(SMC_0603R_H022)'                     | 'RES,8.2K,5%,0.1W,0603'                                                                 | ''        
 'G156-02003-01' | '200KOHM'    | '1%'         = 'SMC_0603R_H022'     | '(SMC_0603R_H022)'                     | 'RES,200K,1%,0.1W,0603'                                                                 | ''        
 'G156-01911-01' | '1.91KOHM'   | '1%'         = 'SMC_0603R_H022'     | '(SMC_0603R_H022)'                     | 'RES,1.91K,1%,0.1W,0603'                                                                | ''        
 'G156-02492-01' | '24.9KOHM'   | '1%'         = 'SMC_0603R_H022'     | '(SMC_0603R_H022)'                     | 'RES,24.9K,1%,0.1W,0603'                                                                | ''        
 'G156-07501-01' | '7.5KOHM'    | '1%'         = 'SMC_0603R_H022'     | '(SMC_0603R_H022)'                     | 'RES,7.5K,1%,0.1W,0603'                                                                 | ''        
 'G156-049R9-01' | '49.9OHM'    | '1%'         = 'SMC_0603R_H022'     | '(SMC_0603R_H022)'                     | 'RES,49.9,1%,0.1W,0603'                                                                 | ''        
 'G156-04422-01' | '44.2KOHM'   | '1%'         = 'SMC_0603R_H022'     | '(SMC_0603R_H022)'                     | 'RES,44.2K,1%,0.1W,0603'                                                                | ''        
 'G156-01002-01' | '10KOHM'     | '1%'         = 'SMC_0603R_H022'     | '(SMC_0603R_H022)'                     | 'RES,10K,1%,0.1W,0603'                                                                  | 'NFND'    
 'G156-07321-01' | '7.32KOHM'   | '1%'         = 'SMC_0603R_H022'     | '(SMC_0603R_H022)'                     | 'RES,7.32K,1%,0.1W,0603'                                                                | ''        
 'G156-04303-01' | '430KOHM'    | '1%'         = 'SMC_0603R_H022'     | '(SMC_0603R_H022)'                     | 'RES,430K,1%,0.1W,0603'                                                                 | ''        
 'G156-01803-01' | '180KOHM'    | '1%'         = 'SMC_0603R_H022'     | '(SMC_0603R_H022)'                     | 'RES,180K,1%,0.1W,0603'                                                                 | ''        
 'G156-01203-01' | '120KOHM'    | '1%'         = 'SMC_0603R_H022'     | '(SMC_0603R_H022)'                     | 'RES,120K,1%,0.1W,0603'                                                                 | ''        
 'G156-01472-01' | '14.7KOHM'   | '1%'         = 'SMC_0603R_H022'     | '(SMC_0603R_H022)'                     | 'RES,14.7K,1%,0.1W,0603'                                                                | ''        
 'G156-02001-01' | '2KOHM'      | '1%'         = 'SMC_0603R_H022'     | '(SMC_0603R_H022)'                     | 'RES,2K,1%,0.1W,0603'                                                                   | ''        
 'G156-04701-01' | '4.7KOHM'    | '1%'         = 'SMC_0603R_H022'     | '(SMC_0603R_H022)'                     | 'RES,4.7K,1%,0.1W,0603'                                                                 | ''        
 'G156-04703-01' | '470KOHM'    | '1%'         = 'SMC_0603R_H022'     | '(SMC_0603R_H022)'                     | 'RES,470K,1%,0.1W,0603'                                                                 | ''        
 'G156-06491-01' | '6.49KOHM'   | '1%'         = 'SMC_0603R_H022'     | '(SMC_0603R_H022)'                     | 'RES,6.49K,1%,0.1W,0603'                                                                | ''        
 'G156-03572-01' | '35.7KOHM'   | '1%'         = 'SMC_0603R_H022'     | '(SMC_0603R_H022)'                     | 'RES,35.7K,1%,0.1W,0603'                                                                | ''        
 'G156-08452-01' | '84.5KOHM'   | '1%'         = 'SMC_0603R_H022'     | '(SMC_0603R_H022)'                     | 'RES,84.5K,1%,0.1W,0603'                                                                | ''        
 'G156-01211-01' | '1.21KOHM'   | '1%'         = 'SMC_0603R_H022'     | '(SMC_0603R_H022)'                     | 'RES,1.21K,1%,0.1W,0603'                                                                | ''        
 'G156-03162-01' | '31.6KOHM'   | '1%'         = 'SMC_0603R_H022'     | '(SMC_0603R_H022)'                     | 'RES,31.6K,1%,0.1W,0603'                                                                | ''        
 'G156-04532-01' | '45.3KOHM'   | '1%'         = 'SMC_0603R_H022'     | '(SMC_0603R_H022)'                     | 'RES,45.3K,1%,0.1W,0603'                                                                | ''        
 'G156-01502-01' | '15KOHM'     | '1%'         = 'SMC_0603R_H022'     | '(SMC_0603R_H022)'                     | 'RES,15K,1%,0.1W,0603'                                                                  | ''        
 'G156-06651-01' | '6.65KOHM'   | '1%'         = 'SMC_0603R_H022'     | '(SMC_0603R_H022)'                     | 'RES,6.65K,1%,0.1W,0603'                                                                | ''        
 'G157-08250-01' | '825OHM'     | '1%'         = 'SMC_0805R_H024'     | '(SMC_0805R_H024)'                     | 'RES,825OHM,1%,0.125W,0805'                                                             | 'NFND'    
 'G156-03483-01' | '348KOHM'    | '1%'         = 'SMC_0603R_H022'     | '(SMC_0603R_H022)'                     | 'RES,348KOHM,1%,0.1W,0603'                                                              | 'NFND'    
 'G156-01603-01' | '160KOHM'    | '1%'         = 'SMC_0603R_H022'     | '(SMC_0603R_H022)'                     | 'RES,160K,1%,0.1W,0603'                                                                 | ''        
 'G156-02703-01' | '270KOHM'    | '1%'         = 'SMC_0603R_H022'     | '(SMC_0603R_H022)'                     | 'RES,270KOHM,1%,0.1W,0603'                                                              | ''        
 'G156-01213-01' | '121KOHM'    | '1%'         = 'SMC_0603R_H022'     | '(SMC_0603R_H022)'                     | 'RES,121K,1%,0.1W,0603'                                                                 | ''        
 'G155-01691-01' | '1.69KOHM'   | '1%'         = 'SMC_0402R_H016'     | '(SMC_0402R_C_H016)'                   | 'RES,1.69K,1%,0.063W,0402'                                                              | ''        
 'G155-02701-01' | '2.7KOHM'    | '1%'         = 'SMC_0402R_H016'     | '(SMC_0402R_C_H016)'                   | 'RES,2.7K,1%,0.0625W,0402'                                                              | ''        
 'G156-03923-01' | '392KOHM'    | '1%'         = 'SMC_0603R_H022'     | '(SMC_0603R_H022)'                     | 'RES,392K,1%,0.1W,0603'                                                                 | ''        
 'G158-06810-01' | '681OHM'     | '1%'         = 'SMC_1206R_H028'     | '(SMC_1206R_H028)'                     | 'RES,681OHM,1%,0.25W,1206'                                                              | ''        
 'G156-01333-01' | '133KOHM'    | '1%'         = 'SMC_0603R_H022'     | '(SMC_0603R_H022)'                     | 'RES,133KOHM,1%,0.1W,0603'                                                              | ''        
 'G156-03903-01' | '390KOHM'    | '1%'         = 'SMC_0603R_H022'     | '(SMC_0603R_H022)'                     | 'RES,390KOHM,1%,0.1W,0603'                                                              | ''        
 'G156-09313-01' | '931KOHM'    | '1%'         = 'SMC_0603R_H022'     | '(SMC_0603R_H022)'                     | 'RES,931KOHM,1%,0.1W,0603'                                                              | ''        
 'G155-01152-01' | '11.5KOHM'   | '1%'         = 'SMC_0402R_H016'     | '(SMC_0402R_C_H016)'                   | 'RES,11.5KOHM,1%,0.063W, 0402'                                                          | ''        
 'G155-080R6-01' | '80.6OHM'    | '1%'         = 'SMC_0402R_H016'     | '(SMC_0402R_C_H016)'                   | 'RES,80.6,1%,0.063W,0402'                                                               | ''        
 'G155-01150-01' | '115OHM'     | '1%'         = 'SMC_0402R_H016'     | '(SMC_0402R_C_H016)'                   | 'RES,115OHM,1%,0.063W,0402'                                                             | ''        
 'G155-08251-01' | '8.25KOHM'   | '1%'         = 'SMC_0402R'          | '(SMC_0402R_C)'                        | 'RES,8.25K,1%,0.063W,0402'                                                              | ''        
 'G155-01153-01' | '115KOHM'    | '1%'         = 'SMC_0402R_H016'     | '(SMC_0402R_C_H016)'                   | 'RES,115KOHM,1%,0.063W, 0402'                                                           | ''        
 'G155-02552-01' | '25.5KOHM'   | '1%'         = 'SMC_0402R_H016'     | '(SMC_0402R_C_H016)'                   | 'RES,25.5K,1%,0.063W,0402'                                                              | ''        
 'G155-01582-01' | '15.8KOHM'   | '1%'         = 'SMC_0402R_H016'     | '(SMC_0402R_C_H016)'                   | 'RES,15.8KOHM,1%,0.063W, 0402'                                                          | ''        
 'G156-05903-01' | '590KOHM'    | '1%'         = 'SMC_0603R_H022'     | '(SMC_0603R_H022)'                     | 'RES,590KOHM,1%,0.1W,0603'                                                              | ''        
 'G155-01432-01' | '14.3KOHM'   | '1%'         = 'SMC_0402R_H016'     | '(SMC_0402R_C_H016)'                   | 'RES,14.3KOHM,1%,0.063W,0402'                                                           | ''        
 'G155-01473-01' | '147KOHM'    | '1%'         = 'SMC_0402R_H016'     | '(SMC_0402R_C_H016)'                   | 'RES,147KOHM,1%,0.063W,0402'                                                            | ''        
 'G156-04753-01' | '475KOHM'    | '1%'         = 'SMC_0603R_H022'     | '(SMC_0603R_H022)'                     | 'RES,475KOHM,1%,0.1W,0603'                                                              | ''        
 'G155-05232-01' | '52.3KOHM'   | '1%'         = 'SMC_0402R_H016'     | '(SMC_0402R_C_H016)'                   | 'RES,52.3KOHM,1%,0.063W,0402'                                                           | ''        
 'G155-01243-01' | '124KOHM'    | '1%'         = 'SMC_0402R_H016'     | '(SMC_0402R_C_H016)'                   | 'RES,124K,1%,1/16W,0402'                                                                | ''        
 'G155-08062-01' | '80.6KOHM'   | '1%'         = 'SMC_0402R_H016'     | '(SMC_0402R_C_H016)'                   | 'RES,80.6KOHM,1%,0.063W,0402'                                                           | ''        
 'G156-05603-01' | '560KOHM'    | '1%'         = 'SMC_0603R_H022'     | '(SMC_0603R_H022)'                     | 'RES,560K,1%,0.1W,0603'                                                                 | ''        
 'G155-06492-01' | '64.9KOHM'   | '1%'         = 'SMC_0402R_H016'     | '(SMC_0402R_C_H016)'                   | 'RES,64.9K,1%,0.0625W,0402'                                                             | ''        
 'G156-01004-01' | '1MOHM'      | '1%'         = 'SMC_0603R_H022'     | '(SMC_0603R_H022)'                     | 'RES,1M,1%,0.1W,0603'                                                                   | ''        
 'G155-02401-01' | '2.4KOHM'    | '1%'         = 'SMC_0402R_H016'     | '(SMC_0402R_C_H016)'                   | 'RES,2.4K,1%0.0625W,0402'                                                               | ''        
 'G155-02400-01' | '240OHM'     | '1%'         = 'SMC_0402R_H016'     | '(SMC_0402R_C_H016)'                   | 'RES,240,1%,0.063W,0402'                                                                | 'NFND'    
 'G155-03000-01' | '300OHM'     | '1%'         = 'SMC_0402R_H016'     | '(SMC_0402R_C_H016)'                   | 'RES,300OHM,1%,0.063W,0402'                                                             | ''        
 'G155-02801-01' | '2.8KOHM'    | '1%'         = 'SMC_0402R'          | '(SMC_0402R_C)'                        | 'RES,2.8K,1%,0.063W,0402'                                                               | ''        
 'G155-030R0-01' | '30OHM'      | '1%'         = 'SMC_0402R_H016'     | '(SMC_0402R_C_H016)'                   | 'RES,30OHM,1%,0.063W,0402'                                                              | ''        
 'G156-08202-01' | '82KOHM'     | '1%'         = 'SMC_0603R_H022'     | '(SMC_0603R_H022)'                     | 'RES,82KOHM,1%,0.1W,0603'                                                               | ''        
 'G155-03001-01' | '3KOHM'      | '1%'         = 'SMC_0402R_H016'     | '(SMC_0402R_C_H016)'                   | 'RES,3K,1%,0.0625W,0402'                                                                | ''        
 'G156-02872-01' | '28.7KOHM'   | '1%'         = 'SMC_0603R_H022'     | '(SMC_0603R_H022)'                     | 'RES,28.7KOHM,1%,0.1W,0603'                                                             | ''        
 'G156-06803-01' | '680KOHM'    | '1%'         = 'SMC_0603R_H022'     | '(SMC_0603R_H022)'                     | 'RES,680KOHM,1%,0.1W,0603'                                                              | ''        
 'G155-015R0-01' | '15OHM'      | '1%'         = 'SMC_0402R_H016'     | '(SMC_0402R_C_H016)'                   | 'RES,15OHM,1%,0.063W,0402'                                                              | ''        
 'G155-03403-01' | '340KOHM'    | '1%'         = 'SMC_0402R_H016'     | '(SMC_0402R_C_H016)'                   | 'RES,340K,1%,0.063W,0402'                                                               | ''        
 'G155-03163-01' | '316KOHM'    | '1%'         = 'SMC_0402R_H016'     | '(SMC_0402R_C_H016)'                   | 'RES,316K,1%,0.063W,0402'                                                               | ''        
 'G155-03011-01' | '3.01KOHM'   | '1%'         = 'SMC_0402R'          | '(SMC_0402R_C,C0402-0P8MM-45DG)'                        | 'RES,3.01K,1%,0.063W,0402'                                                              | ''        
 'G155-01873-01' | '187KOHM'    | '1%'         = 'SMC_0402R_H016'     | '(SMC_0402R_C_H016)'                   | 'RES,187KOHM,1%,0.063W,0402'                                                            | ''        
 'G157-03R01-01' | '3.01OHM'    | '1%'         = 'SMC_0805R_H024'     | '(SMC_0805R_H024)'                     | 'RES, 3.01OHM, 1%, 0.125W, 0805'                                                        | ''        
 'G155-024R9-01' | '24.9OHM'    | '1%'         = 'SMC_0402R_H016'     | '(SMC_0402R_C_H016)'                   | 'RES,24.9,1%,0.063W,0402'                                                               | ''        
 'G155-01202-01' | '12KOHM'     | '1%'         = 'SMC_0402R'          | '(SMC_0402R_C)'                        | 'RES,12K,1%,0.063W,0402'                                                                | ''        
 'G155-03832-01' | '38.3KOHM'   | '1%'         = 'SMC_0402R_H016'     | '(SMC_0402R_C_H016)'                   | 'RES,38.3K,1%,0.063W,0402'                                                              | ''        
 'G155-04702-01' | '47KOHM'     | '1%'         = 'SMC_0402R_H016'     | '(SMC_0402R_C_H016)'                   | 'RES,47K,1%,0.0625,0402'                                                                | ''        
 'G155-09092-01' | '90.9KOHM'   | '1%'         = 'SMC_0402R'          | '(SMC_0402R_C)'                        | 'RES,90.9K,1%,0.063W,0402'                                                              | ''        
 'G156-07502-01' | '75KOHM'     | '1%'         = 'SMC_0603R_H022'     | '(SMC_0603R_H022)'                     | 'RES,75K,1%,0.1W,0603'                                                                  | ''        
 'G156-03163-01' | '316KOHM'    | '1%'         = 'SMC_0603R_H022'     | '(SMC_0603R_H022)'                     | 'RES,316K,1%,0.1W,0603'                                                                 | ''        
 'G158-01002-01' | '10KOHM'     | '1%'         = 'SMC_1206R_H028'     | '(SMC_1206R_H028)'                     | 'RES, 10KOHMS, 1%, 0.25W, 1206, ROHS'                                                   | ''        
 'G158-06491-01' | '6.49KOHM'   | '1%'         = 'SMC_1206R_H028'     | '(SMC_1206R_H028)'                     | 'RES, 6.49KOHMS, 1%, 0.25W, 1206, ROHS'                                                 | ''        
 'G158-05493-01' | '549KOHM'    | '1%'         = 'SMC_1206R_H028'     | '(SMC_1206R_H028)'                     | 'RES, 549KOHMS, 1%, 0.25W, 1206, ROHS'                                                  | ''        
 'G158-05112-01' | '51.1KOHM'   | '1%'         = 'SMC_1206R_H028'     | '(SMC_1206R_H028)'                     | 'RES, 51.1K, 1%,0.25W, 1206'                                                            | ''        
 'G155-06202-01' | '62KOHM'     | '1%'         = 'SMC_0402R_H016'     | '(SMC_0402R_C_H016)'                   | 'RES, 62K, 1%, 0.0625, 0402'                                                            | ''        
 'G156-01500-01' | '150OHM'     | '1%'         = 'SMC_0603R'          | '(SMC_0603R)'                          | 'RES,150,1%,0.1W,0603'                                                                  | 'NFND'    
 'G156-01000-01' | '100OHM'     | '1%'         = 'SMC_0603R'          | '(SMC_0603R)'                          | 'RES,100,1%,0.1W,0603'                                                                  | 'NFND'    
 'G152-10138-01' | '13KOHM'     | '1%'         = 'SMC_1210R_H028'     | '(SMC_1210R_H028)'                     | 'RES, 13K, 0.33W, 1%, 1210'                                                             | 'NFND'    
 'G155-04641-01' | '4.64KOHM'   | '1%'         = 'SMC_0402R_H016'     | '(SMC_0402R_C_H016)'                   | 'RES,4.64K,1%,0.0625W,0402'                                                             | ''        
 'G155-020R0-01' | '20OHM'      | '1%'         = 'SMC_0402R'          | '(SMC_0402R_C)'                        | 'RES,20,1%,0.063W,0402'                                                                 | 'NFND'    
 'G156-06193-01' | '619KOHM'    | '1%'         = 'SMC_0603R_H022'     | '(SMC_0603R_H022)'                     | 'RES,619K,1%,0.1W,0603'                                                                 | ''        
 'G157-09531-01' | '9.53KOHM'   | '1%'         = 'SMC_0805R_H024'     | '(SMC_0805R_H024)'                     | 'RES,9.53K,1%,0.125W,0805'                                                              | 'NFND'    
 'G152-10147-01' | '18.2KOHM'   | '0.1%'       = 'SMC_0603R_H022'     | '(SMC_0603R_H022)'                     | 'RES,18.2K,0.1%,0.063W,0603'                                                            | ''        
 'G152-10148-01' | '51.1KOHM'   | '0.1%'       = 'SMC_0603R_H022'     | '(SMC_0603R_H022)'                     | 'RES,51.1K,0.1%,0.063W,0603'                                                            | ''        
 'G156-01052-01' | '10.5KOHM'   | '1%'         = 'SMC_0603R'          | '(SMC_0603R)'                          | 'RES,10.5K,1%,0.1W,0603'                                                                | ''        
 'G155-06191-01' | '6.19KOHM'   | '1%'         = 'SMC_0402R'          | '(SMC_0402R_C)'                        | 'RES,6.19K,1%,0.063W,0402'                                                              | ''        
 'G156-08251-01' | '8.25KOHM'   | '1%'         = 'SMC_0603R'          | '(SMC_0603R)'                          | 'RES,8.25K,1%,0.1W,0603'                                                                | ''        
 'G156-040R2-01' | '40.2OHM'    | '1%'         = 'SMC_0603R_H022'     | '(SMC_0603R_H022)'                     | 'RES,40.2,1%,0.1W,0603'                                                                 | ''        
 'G155-03480-01' | '348OHM'     | '1%'         = 'SMC_0402R_H016'     | '(SMC_0402R_C_H016)'                   | 'RES,348OHM,1%,0.063W,0402'                                                             | ''        
 'G155-01300-01' | '130OHM'     | '1%'         = 'SMC_0402R_H016'     | '(SMC_0402R_C_H016)'                   | 'RES,130,1%,0.063W,0402'                                                                | ''        
 'G155-082R0-01' | '82OHM'      | '1%'         = 'SMC_0402R_H016'     | '(SMC_0402R_C_H016)'                   | 'RES,82OHM,1%,0.063W,0402'                                                              | ''        
 'G156-01204-01' | '1.2MOHM'    | '1%'         = 'SMC_0603R_H022'     | '(SMC_0603R_H022)'                     | 'RES,1.2M,1%,0.1W,0603'                                                                 | ''        
 'G155-08060-01' | '806OHM'     | '1%'         = 'SMC_0402R'          | '(SMC_0402R_C)'                        | 'RES,806,1%,0.063W,0402'                                                                | ''        
 'G152-10156-01' | '0OHM'       | '-'          = 'SMC_1210R_H028'     | '(SMC_1210R_H028)'                     | 'RES,0OHM,2A,1210'                                                                      | ''        
 'G158-05113-01' | '511KOHM'    | '1%'         = 'SMC_1206R_H028'     | '(SMC_1206R_H028)'                     | 'RES,511K,1%,0.25W,1206'                                                                | ''        
 'G156-01783-01' | '178KOHM'    | '1%'         = 'SMC_0603R_H022'     | '(SMC_0603R_H022)'                     | 'RES,178K,1%,0.1W,0603'                                                                 | ''        
 'G155-01622-01' | '16.2KOHM'   | '1%'         = 'SMC_0402R_H016'     | '(SMC_0402R_C_H016)'                   | 'RES,16.2K,1%,0.063W,0402'                                                              | ''        
 'G152-10115-01' | '0.003OHM'   | '1%'         = 'SMC_2512R_V2'       | '(SMC_2512R_V2)'                       | 'RES,0.003,1%,2W,2512'                                                                  | ''        
 'G155-07501-01' | '7.5KOHM'    | '1%'         = 'SMC_0402R_H016'     | '(SMC_0402R_C_H016)'                   | 'RES,SMT,7.5K,1%,1/16W,0402'                                                            | ''        
 'G152-10195-01' | '86.6KOHM'   | '1%'         = 'SMC_0402R_H014'     | '(SMC_0402R_C_H014)'                   | 'RES,86.6K,1%,0.063W,0402,THIN'                                                         | ''        
 'G152-10160-01' | '0.004OHM'   | '1%'         = 'SMC_2512R_V2'       | '(SMC_2512R_V2)'                       | 'RES,0.004OHM,1%,2W,2512'                                                               | ''        
 'G158-02003-01' | '200KOHM'    | '1%'         = 'SMC_1206R_H026'     | '(SMC_1206R_H026)'                     | 'RES,200K,1%,0.25W,1206'                                                                | ''        
 'G158-04991-01' | '4.99KOHM'   | '1%'         = 'SMC_1206R_H026'     | '(SMC_1206R_H026)'                     | 'RES,4.99K,1%,0.25W,1206'                                                               | ''        
 'G158-03921-01' | '3.92KOHM'   | '1%'         = 'SMC_1206R_H026'     | '(SMC_1206R_H026)'                     | 'RES,3.92K,1%,0.25W,1206'                                                               | ''        
 'G155-03162-01' | '31.6KOHM'   | '1%'         = 'SMC_0402R_H016'     | '(SMC_0402R_C_H016)'                   | 'RES,31.6K,1%,0.063W,0402'                                                              | ''        
 'G155-03902-01' | '39KOHM'     | '1%'         = 'SMC_0402R_H014'     | '(SMC_0402R_C_H014)'                   | 'RES, 39K, 1%, 0.063W, 0402'                                                            | ''        
 'G155-01132-01' | '11.3KOHM'   | '1%'         = 'SMC_0402R'          | '(SMC_0402R_C)'                        | 'RES,11.3K,1%,0.063W,0402'                                                              | ''        
 'G155-01693-01' | '169KOHM'    | '1%'         = 'SMC_0402R_H016'     | '(SMC_0402R_C_H016)'                   | 'RES,169K,1%,0.0625W,0402'                                                              | ''        
 'G155-08872-01' | '88.7KOHM'   | '1%'         = 'SMC_0402R_H014'     | '(SMC_0402R_C_H014)'                   | 'RES,88.7K,1%,0.0625W,0402'                                                             | ''        
 'G152-10201-01' | '33KOHM'     | '1%'         = 'SMC_0402R_H014'     | '(SMC_0402R_C_H014)'                   | 'RES,33K,1%,0.0625W,0402,THIN'                                                          | ''        
 'G152-10196-01' | '61.9KOHM'   | '1%'         = 'SMC_0402R_H014'     | '(SMC_0402R_C_H014)'                   | 'RES,61.9K,1%,0.0625W,0402,THIN'                                                        | ''        
 'G155-00682-01' | '6.8KOHM'    | '1%'         = 'SMC_0402R_H014'     | '(SMC_0402R_C_H014)'                   | 'RES,6.8K,1%,0.0625W,0402'                                                              | ''        
 'G155-00913-01' | '91KOHM'     | '1%'         = 'SMC_0402R_H016'     | '(SMC_0402R_C_H016)'                   | 'RES,91K,1%,0.0625W,0402'                                                               | ''        
 'G156-02000-01' | '200OHM'     | '1%'         = 'SMC_0603R'          | '(SMC_0603R)'                          | 'RES,200,1%,0.1W,0603'                                                                  | ''        
 'G155-03300-01' | '330OHM'     | '1%'         = 'SMC_0402R_H016'     | '(SMC_0402R_C_H016)'                   | 'RES,330,1%,0.063W,0402'                                                                | 'NFND'    
 'G156-09092-01' | '90.9KOHM'   | '1%'         = 'SMC_0603R_H022'     | '(SMC_0603R_H022)'                     | 'RES,90.9K,1%,0.1W,0603'                                                                | ''        
 'G158-01201-01' | '1.2KOHM'    | '1%'         = 'SMC_1206R_H026'     | '(SMC_1206R_H026)'                     | 'RES,1.2K,1%,0.25W,1206'                                                                | ''        
 'G158-02152-01' | '21.5KOHM'   | '1%'         = 'SMC_1206R_H026'     | '(SMC_1206R_H026)'                     | 'RES, 21.5KOHM, 1%, 0.25W, 1206'                                                        | ''        
 'G155-05112-01' | '51.1KOHM'   | '1%'         = 'SMC_0402R'          | '(SMC_0402R_C)'                        | 'RES, 51.1K,1%,0.063W,0402'                                                             | ''        
 'G155-01822-01' | '18.2KOHM'   | '1%'         = 'SMC_0402R_H014'     | '(SMC_0402R_C_H014)'                   | 'RES, 18.2KOHM, 1%, 0.0625W, 0402'                                                      | ''        
 'G158-04300-01' | '430OHM'     | '1%'         = 'SMC_1206R_H026'     | '(SMC_1206R_H026)'                     | 'RES, 430OHM, 1%, 0.25W, 1206'                                                          | ''        
 'G158-03600-01' | '360OHM'     | '1%'         = 'SMC_1206R_H026'     | '(SMC_1206R_H026)'                     | 'RES, 360OHM, 1%, 0.25W, 1206'                                                          | ''        
 'G155-04300-01' | '430OHM'     | '1%'         = 'SMC_0402R_H014'     | '(SMC_0402R_C_H014)'                   | 'RES, 430OHM, 1%, 0.0625W, 0402'                                                        | ''        
 'G155-08450-01' | '845OHM'     | '1%'         = 'SMC_0402R_H014'     | '(SMC_0402R_C_H014)'                   | 'RES, 845OHM, 1%, 0.0625W, 0402'                                                        | ''        
 'G155-03301-01' | '3.3KOHM'    | '1%'         = 'SMC_0402R_H016'     | '(SMC_0402R_C_H016)'                   | 'RES,SMT,3.3K,1%,1/16W,0402'                                                            | 'NFND'    
 'G156-03003-01' | '300KOHM'    | '1%'         = 'SMC_0603R_H022'     | '(SMC_0603R_H022)'                     | 'RES,300K,1%,0.1W,0603'                                                                 | ''        
 'G156-02322-01' | '23.2KOHM'   | '1%'         = 'SMC_0603R'          | '(SMC_0603R)'                          | 'RES,23.2K,1%,0.0625W,0603'                                                             | ''        
 'G155-01782-01' | '17.8KOHM'   | '1%'         = 'SMC_0402R_H016'     | '(SMC_0402R_C_H016)'                   | 'RES,17.8K,1%,0.063W,0402'                                                              | ''        
 'G152-10168-01' | '88.7KOHM'   | '0.1%'       = 'SMC_0402R_H014'     | '(SMC_0402R_C_H014)'                   | 'RES,88.7K,0.1%,0.0625W,0402'                                                           | ''        
 'G156-08451-01' | '8.45KOHM'   | '1%'         = 'SMC_0603R_H024'     | '(SMC_0603R_H024)'                     | 'RES,8.45K,1%,0.1W,0603'                                                                | ''        
 'G156-08203-01' | '820KOHM'    | '1%'         = 'SMC_0603R_H022'     | '(SMC_0603R_H022)'                     | 'RES,820K,1%,0.1W,0603'                                                                 | ''        
 'G155-03601-01' | '3.6KOHM'    | '1%'         = 'SMC_0402R_H016'     | '(SMC_0402R_C_H016)'                   | 'RES,3.6K,1%,0.0625W,0402'                                                              | 'NFND'    
 'G156-005R1-05' | '5.1OHM'     | '5%'         = 'SMC_0603R'          | '(SMC_0603R)'                          | 'RES,5.1,5%,0.1W,0603'                                                                  | ''        
 'G155-02872-01' | '28.7KOHM'   | '1%'         = 'SMC_0402R_H016'     | '(SMC_0402R_C_H016)'                   | 'RES,28.7K,1%,0.063W,0402'                                                              | ''        
 'G155-02003-01' | '200KOHM'    | '1%'         = 'SMC_0402R_H016'     | '(SMC_0402R_C_H016)'                   | 'RES,200K,1%,0.063W,0402'                                                               | ''        
 'G156-020R0-01' | '20OHM'      | '1%'         = 'SMC_0603R_H022'     | '(SMC_0603R_H022)'                     | 'RES,20OHM,1%,0.1W,0603'                                                                | ''        
 'G155-03R00-01' | '3OHM'       | '1%'         = 'SMC_0402R_H016'     | '(SMC_0402R_C_H016)'                   | 'RES,3OHM,1%,0.063W,0402'                                                               | ''        
 'G155-043R0-01' | '43OHM'      | '1%'         = 'SMC_0402R_H016'     | '(SMC_0402R_C_H016)'                   | 'RES,43OHM,1%,0.063W,0402'                                                              | ''        
 'G155-02703-01' | '270KOHM'    | '1%'         = 'SMC_0402R_H016'     | '(SMC_0402R_C_H016)'                   | 'RES,270KOHM,1%,0.063W,0402'                                                            | ''        
 'G155-02001-01' | '2KOHM'      | '1%'         = 'SMC_0402R'          | '(SMC_0402R_C)'                        | 'RES,2K,1%,0.063W,0402'                                                                 | 'NFND'    
 'G155-06192-01' | '61.9KOHM'   | '1%'         = 'SMC_0402R_H016'     | '(SMC_0402R_C_H016)'                   | 'RES,61.9K,1%,0.0625W,0402'                                                             | ''        
 'G155-08662-01' | '86.6KOHM'   | '1%'         = 'SMC_0402R_H016'     | '(SMC_0402R_C_H016)'                   | 'RES,86.6K,1%,0.063W,0402'                                                              | ''        
 'G155-075R0-01' | '75OHM'      | '1%'         = 'SMC_0402R_H016'     | '(SMC_0402R_C_H016)'                   | 'RES,75,1%,0.063W,0402'                                                                 | ''        
 'G158-04700-01' | '470OHM'     | '1%'         = 'SMC_1206R_H028'     | '(SMC_1206R_H028)'                     | 'RES, 470OHM, 1%, 0.25W, 1206'                                                          | ''        
 'G158-060R4-01' | '60.4OHM'    | '1%'         = 'SMC_1206R_H028'     | '(SMC_1206R_H028)'                     | 'RES, 60.4OHM, 1%, 0.25W, 1206'                                                         | ''        
 'G152-10199-01' | '100OHM'     | '1%'         = 'SMC_1210R_H028'     | '(SMC_1210R_H028)'                     | 'RES, 100OHM, 1%, 0.5W, 1210'                                                           | ''        
 'G158-04301-01' | '4.3KOHM'    | '1%'         = 'SMC_1206R_H028'     | '(SMC_1206R_H028)'                     | 'RES,4.3KOHM,1%,0.25W,-55/125C,1206'                                                    | ''        
 'G158-04421-01' | '4.42KOHM'   | '1%'         = 'SMC_1206R_H030'     | '(SMC_1206R_H030)'                     | 'RES, 4.42KOHM, 1%, 0.25W, 1206'                                                        | ''        
 'G155-00222-05' | '2.2KOHM'    | '5%'         = 'SMC_0402R_H016'     | '(SMC_0402R_C_H016)'                   | 'RES,2.2K,5%,0.1W,0402'                                                                 | 'NFND'    
 'G155-01213-01' | '121KOHM'    | '1%'         = 'SMC_0402R_H016'     | '(SMC_0402R_C_H016)'                   | 'RES,121K,1%,0.063W,0402'                                                               | ''        
 'G155-05603-01' | '560KOHM'    | '1%'         = 'SMC_0402R_H016'     | '(SMC_0402R_C_H016)'                   | 'RES,560K,1%,0.0625W,0402'                                                              | ''        
 'G155-08452-01' | '84.5KOHM'   | '1%'         = 'SMC_0402R_H016'     | '(SMC_0402R_C_H016)'                   | 'RES,84.5K,1%,0.0625W,0402 '                                                            | ''        
 'G155-03572-01' | '35.7KOHM'   | '1%'         = 'SMC_0402R_H016'     | '(SMC_0402R_C_H016)'                   | 'RES,35.7K,1%,0.063W,0402'                                                              | ''        
 'G155-03003-01' | '300KOHM'    | '1%'         = 'SMC_0402R_H016'     | '(SMC_0402R_C_H016)'                   | 'RES,300KOHM,1%,0.0625W,0402'                                                           | ''        
 'G155-06201-01' | '6.2KOHM'    | '1%'         = 'SMC_0402R_H016'     | '(SMC_0402R_C_H016)'                   | 'RES, 6.2KOHM,1%, 0.063W ,0402'                                                         | ''        
 'G155-030R1-01' | '30.1OHM'    | '1%'         = 'SMC_0402R_H016'     | '(SMC_0402R_C_H016)'                   | 'RES, 30.1, 1%, 0.063W, 0402'                                                           | ''        
 'G155-04020-01' | '402OHM'     | '1%'         = 'SMC_0402R_H016'     | '(SMC_0402R_C_H016)'                   | 'RES,402,1%,0.063W,0402'                                                                | ''        
 'G155-045R3-01' | '45.3OHM'    | '1%'         = 'SMC_0402R_H016'     | '(SMC_0402R_C_H016)'                   | 'RES,45.3,1%,0.063W,0402'                                                               | ''        
 'G155-02210-01' | '221OHM'     | '1%'         = 'SMC_0402R'          | '(SMC_0402R_C)'                        | 'RES,221,1%,0.063W,0402'                                                                | ''        
 'G155-023R7-01' | '23.7OHM'    | '1%'         = 'SMC_0402R_H016'     | '(SMC_0402R_C_H016)'                   | 'RES,23.7,1%,0.063W,0402'                                                               | ''        
 'G155-01620-01' | '162OHM'     | '1%'         = 'SMC_0402R_H016'     | '(SMC_0402R_C_H016)'                   | 'RES,162,1%,0.063W,0402'                                                                | ''        
 'G155-056R2-01' | '56.2OHM'    | '1%'         = 'SMC_0402R_H016'     | '(SMC_0402R_C_H016)'                   | 'RES,56.2,1%,0.063W,0402'                                                               | ''        
 'G155-002R2-05' | '2.2OHM'     | '5%'         = 'SMC_0402R_H016'     | '(SMC_0402R_C_H016)'                   | 'RES,2.2,5%,0.063W,0402'                                                                | ''        
 'G155-01372-01' | '13.7KOHM'   | '1%'         = 'SMC_0402R_H016'     | '(SMC_0402R_C_H016)'                   | 'RES,13.7K,1%,0.063W,0402'                                                              | ''        
 'G155-02051-01' | '2.05KOHM'   | '1%'         = 'SMC_0402R_H016'     | '(SMC_0402R_C_H016)'                   | 'RES,2.05K,1%,0.063W,0402'                                                              | ''        
 'G155-02052-01' | '20.5KOHM'   | '1%'         = 'SMC_0402R_H016'     | '(SMC_0402R_C_H016)'                   | 'RES,20.5K,1%,0.063W,0402'                                                              | ''        
 'G155-02371-01' | '2.37KOHM'   | '1%'         = 'SMC_0402R_H016'     | '(SMC_0402R_C_H016)'                   | 'RES,2.37K,1%,0.063W,0402'                                                              | ''        
 'G155-03240-01' | '324OHM'     | '1%'         = 'SMC_0402R_H016'     | '(SMC_0402R_C_H016)'                   | 'RES,324,1%,0.063W,0402'                                                                | ''        
 'G155-03651-01' | '3.65KOHM'   | '1%'         = 'SMC_0402R_H016'     | '(SMC_0402R_C_H016)'                   | 'RES,3.65K,1%,0.063W,0402'                                                              | ''        
 'G155-03742-01' | '37.4KOHM'   | '1%'         = 'SMC_0402R_H016'     | '(SMC_0402R_C_H016)'                   | 'RES,37.4K,1%,0.063W,0402'                                                              | ''        
 'G155-03921-01' | '3.92KOHM'   | '1%'         = 'SMC_0402R'          | '(SMC_0402R_C)'                        | 'RES,3.92K,1%,0.063W,0402'                                                              | ''        
 'G155-04871-01' | '4.87KOHM'   | '1%'         = 'SMC_0402R'          | '(SMC_0402R_C)'                        | 'RES,4.87K,1%,0.063W,0402'                                                              | ''        
 'G155-04993-01' | '499KOHM'    | '1%'         = 'SMC_0402R_H016'     | '(SMC_0402R_C_H016)'                   | 'RES,499K,1%,0.063W,0402'                                                               | ''        
 'G155-05361-01' | '5.36KOHM'   | '1%'         = 'SMC_0402R_H016'     | '(SMC_0402R_C_H016)'                   | 'RES,5.36K,1%,0.063W,0402'                                                              | ''        
 'G155-05490-01' | '549OHM'     | '1%'         = 'SMC_0402R'          | '(SMC_0402R_C)'                        | 'RES,549,1%,0.063W,0402'                                                                | ''        
 'G155-08661-01' | '8.66KOHM'   | '1%'         = 'SMC_0402R'          | '(SMC_0402R_C)'                        | 'RES,8.66K,1%,0.063W,0402'                                                              | ''        
 'G155-09311-01' | '9.31KOHM'   | '1%'         = 'SMC_0402R_H016'     | '(SMC_0402R_C_H016)'                   | 'RES,9.31K,1%,0.063W,0402'                                                              | ''        
 'G155-01102-01' | '11KOHM'     | '1%'         = 'SMC_0402R_H016'     | '(SMC_0402R_C_H016)'                   | 'RES,11.0K,1%,0.063W,0402'                                                              | ''        
 'G155-06812-01' | '68.1KOHM'   | '1%'         = 'SMC_0402R_H016'     | '(SMC_0402R_C_H016)'                   | 'RES,68.1K,1%,0.063W,0402'                                                              | ''        
 'G155-05622-01' | '56.2KOHM'   | '1%'         = 'SMC_0402R_H016'     | '(SMC_0402R_C_H016)'                   | 'RES,56.2K,1%,0.063W,0402'                                                              | ''        
 'G155-07870-01' | '787OHM'     | '1%'         = 'SMC_0402R_H016'     | '(SMC_0402R_C_H016)'                   | 'RES,787,1%,0.063W,0402'                                                                | ''        
 'G156-03242-01' | '32.4KOHM'   | '1%'         = 'SMC_0603R_H022'     | '(SMC_0603R_H022)'                     | 'RES,32.4K,1%,0.1W,0603'                                                                | ''        
 'G156-01242-01' | '12.4KOHM'   | '1%'         = 'SMC_0603R_H022'     | '(SMC_0603R_H022)'                     | 'RES,12.4K,1%,0.1W,0603'                                                                | ''        
 'G156-06342-01' | '63.4KOHM'   | '1%'         = 'SMC_0603R_H022'     | '(SMC_0603R_H022)'                     | 'RES,63.4K,1%,0.1W,0603'                                                                | ''        
 'G155-01005-01' | '10MOHM'     | '1%'         = 'SMC_0402R_H016'     | '(SMC_0402R_C_H016)'                   | 'RES,10M,1%,0.063W,0402'                                                                | ''        
 'G155-02152-01' | '21.5KOHM'   | '1%'         = 'SMC_0402R_H016'     | '(SMC_0402R_C_H016)'                   | 'RES,21.5K,1%,0.0625W,0402'                                                             | ''        
 'G152-10225-01' | '10KOHM'     | '1%'         = 'SMC_2512R_H028'     | '(SMC_2512R_H028)'                     | 'RES,10K,1%,1W,2512'                                                                    | ''        
 'G155-04990-01' | '499OHM'     | '1%'         = 'SMC_0402R'          | '(SMC_0402R_C)'                        | 'RES, 499,1%,0.063W,0402'                                                               | ''        
 'G155-05104-01' | '5.1MOHM'    | '1%'         = 'SMC_0402R_H016'     | '(SMC_0402R_C_H016)'                   | 'RES,5.1MOHM,1%,0.063W,0402'                                                            | ''        
 'G155-07682-01' | '76.8KOHM'   | '1%'         = 'SMC_0402R_H016'     | '(SMC_0402R_C_H016)'                   | 'RES,76.8K,1%,0.0625W,0402'                                                             | ''        
 'G155-01823-01' | '182KOHM'    | '1%'         = 'SMC_0402R_H016'     | '(SMC_0402R_C_H016)'                   | 'RES,182K,1%,0.063W,0402'                                                               | ''        
 'G155-03573-01' | '357KOHM'    | '1%'         = 'SMC_0402R_H016'     | '(SMC_0402R_C_H016)'                   | 'RES,357K,1%,0.063W,0402'                                                               | ''        
 'G155-02611-01' | '2.61KOHM'   | '1%'         = 'SMC_0402R_H016'     | '(SMC_0402R_C_H016)'                   | 'RES,2.61K,1%,0.063W,0402'                                                              | ''        
 'G155-01503-01' | '150KOHM'    | '1%'         = 'SMC_0402R_H016'     | '(SMC_0402R_C_H016)'                   | 'RES,150K,1%,0.063W,0402'                                                               | ''        
 'G155-04122-01' | '41.2KOHM'   | '1%'         = 'SMC_0402R_H016'     | '(SMC_0402R_C_H016)'                   | 'RES,41.2K,1%,0.063W,0402'                                                              | ''        
 'G155-08663-01' | '866KOHM'    | '1%'         = 'SMC_0402R_H016'     | '(SMC_0402R_C_H016)'                   | 'RES,866K,1%,0.063W,0402'                                                               | ''        
 'G155-027R0-01' | '27OHM'      | '1%'         = 'SMC_0402R_H016'     | '(SMC_0402R_C_H016)'                   | 'RES,27,1%,0.0625W,0402'                                                                | ''        
 'G155-06651-01' | '6.65KOHM'   | '1%'         = 'SMC_0402R'          | '(SMC_0402R_C)'                        | 'RES,6.65K,1%,0.063W,0402'                                                              | ''        
 'G155-01001-01' | '1KOHM'      | '1%'         = 'SMC_0402R'          | '(SMC_0402R_C,C0402_BGA)'                        | 'RES,1K,1%,0.063W,0402'                                                                 | 'NFND'    
 'G155-01002-01' | '10KOHM'     | '1%'         = 'SMC_0402R'          | '(SMC_0402R_C)'                        | 'RES,10K,1%,0.063W,0402'                                                                | 'NFND'    
 'G155-02101-01' | '2.1KOHM'    | '1%'         = 'SMC_0402R'          | '(SMC_0402R_C)'                        | 'RES,2.1K,1%,0.063W,0402'                                                               | ''        
 'G155-01742-01' | '17.4KOHM'   | '1%'         = 'SMC_0402R_H016'     | '(SMC_0402R_C_H016)'                   | 'RES,17.4K,1%,0.063W,0402'                                                              | ''        
 'G155-02871-01' | '2.87KOHM'   | '1%'         = 'SMC_0402R'          | '(SMC_0402R_C)'                        | 'RES,2.87K,1%,0.063W,0402'                                                              | ''        
 'G155-02431-01' | '2.43KOHM'   | '1%'         = 'SMC_0402R'          | '(SMC_0402R_C)'                        | 'RES,2.43K,1%,0.063W,0402'                                                              | ''        
 'G155-09091-01' | '9.09KOHM'   | '1%'         = 'SMC_0402R_H016'     | '(SMC_0402R_C_H016)'                   | 'RES,9.09K,1%,0.0625W,0402'                                                             | ''        
 'G155-05621-01' | '5.62KOHM'   | '1%'         = 'SMC_0402R_H016'     | '(SMC_0402R_C_H016)'                   | 'RES,5.62K,1%,0.0625W,0402'                                                             | ''        
 'G155-06190-01' | '619OHM'     | '1%'         = 'SMC_0402R_H016'     | '(SMC_0402R_C_H016)'                   | 'RES,619,1%,0.063W,0402'                                                                | ''        
 'G155-000R0-05' | '0OHM'       | '5%'         = 'SMC_0402R'          | '(SMC_0402R_C,C0402-0P8MM-45DG)'                        | 'RES,0,5%,0.063W,0402'                                                                  | 'NFND'    
 'G155-02432-01' | '24.3KOHM'   | '1%'         = 'SMC_0402R_H016'     | '(SMC_0402R_C_H016)'                   | 'RES,24.3K,1%,0.063W,0402'                                                              | ''        
 'G155-01743-01' | '174KOHM'    | '1%'         = 'SMC_0402R_H016'     | '(SMC_0402R_C_H016)'                   | 'RES,174K,1%,0.0625W,0402'                                                              | ''        
 'G155-02102-01' | '21KOHM'     | '1%'         = 'SMC_0402R'          | '(SMC_0402R_C)'                        | 'RES,21K,1%,0.063W,0402'                                                                | ''        
 'G155-05362-01' | '53.6KOHM'   | '1%'         = 'SMC_0402R_H016'     | '(SMC_0402R_C_H016)'                   | 'RES,53.6K,1%,0.0625W,0402'                                                             | ''        
 'G155-03481-01' | '3.48KOHM'   | '1%'         = 'SMC_0402R_H016'     | '(SMC_0402R_C_H016)'                   | 'RES,3.48K,1%,0.063W,0402'                                                              | ''        
 'G155-02741-01' | '2.74KOHM'   | '1%'         = 'SMC_0402R'          | '(SMC_0402R_C)'                        | 'RES,2.74K,1%,0.063W,0402'                                                              | ''        
 'G155-01821-01' | '1.82KOHM'   | '1%'         = 'SMC_0402R_H016'     | '(SMC_0402R_C_H016)'                   | 'RES,1.82K,1%,0.063W,0402'                                                              | ''        
 'G155-02261-01' | '2.26KOHM'   | '1%'         = 'SMC_0402R_H016'     | '(SMC_0402R_C_H016)'                   | 'RES,2.26K,1%,0.0625W,0402'                                                             | ''        
 'G155-05761-01' | '5.76KOHM'   | '1%'         = 'SMC_0402R_H016'     | '(SMC_0402R_C_H016)'                   | 'RES,5.76K,1%,0.063W,0402'                                                              | ''        
 'G155-010R0-01' | '10OHM'      | '1%'         = 'SMC_0402R'          | '(SMC_0402R_C)'                        | 'RES,10,1%,0.063W,0402'                                                                 | 'NFND'    
 'G155-033R2-01' | '33.2OHM'    | '1%'         = 'SMC_0402R'          | '(SMC_0402R_C)'                        | 'RES,33.2,1%,0.063W,0402'                                                               | ''        
 'G152-10228-01' | '10MOHM'     | '1%'         = 'SMC_2010R_H028'     | '(SMC_2010R_H028)'                     | 'RES,10MOHM,1%,0.5W,2010'                                                               | ''        
 'G155-02612-01' | '26.1KOHM'   | '1%'         = 'SMC_0402R'          | '(SMC_0402R_C)'                        | 'RES,26.1K,1%,0.063W,0402'                                                              | ''        
 'G155-01400-01' | '140OHM'     | '1%'         = 'SMC_0402R_H016'     | '(SMC_0402R_C_H016)'                   | 'RES,140,1%,0.063W,0402'                                                                | ''        
 'G155-01000-01' | '100OHM'     | '1%'         = 'SMC_0402R'          | '(SMC_0402R_C)'                        | 'RES,100,1%,0.0625W,0402'                                                               | 'NFND'    
 'G155-01003-01' | '100KOHM'    | '1%'         = 'SMC_0402R'          | '(SMC_0402R_C)'                        | 'RES,100K,1%,0.063W,0402'                                                               | 'NFND'    
 'G155-01302-01' | '13KOHM'     | '1%'         = 'SMC_0402R_H016'     | '(SMC_0402R_C_H016)'                   | 'RES,13K,1%,0.063W,0402'                                                                | ''        
 'G155-02002-01' | '20KOHM'     | '1%'         = 'SMC_0402R_H016'     | '(SMC_0402R_C_H016)'                   | 'RES,20K,1%,0.063W,0402'                                                                | 'NFND'    
 'G155-06041-01' | '6.04KOHM'   | '1%'         = 'SMC_0402R'          | '(SMC_0402R_C)'                        | 'RES,6.04K,1%,0.063W,0402'                                                              | ''        
 'G155-03242-01' | '32.4KOHM'   | '1%'         = 'SMC_0402R_H016'     | '(SMC_0402R_C_H016)'                   | 'RES,32.4K,1%,0.063W,0402'                                                              | ''        
 'G155-01402-01' | '14KOHM'     | '1%'         = 'SMC_0402R_H016'     | '(SMC_0402R_C_H016)'                   | 'RES,14K,1%,0.063W,0402'                                                                | ''        
 'G155-01501-01' | '1.5KOHM'    | '1%'         = 'SMC_0402R'          | '(SMC_0402R_C)'                        | 'RES,1.5K,1%,0.063W,0402'                                                               | 'NFND'    
 'G155-01210-01' | '121OHM'     | '1%'         = 'SMC_0402R_H016'     | '(SMC_0402R_C_H016)'                   | 'RES,121,1%,0.063W,0402'                                                                | ''        
 'G155-02491-01' | '2.49KOHM'   | '1%'         = 'SMC_0402R'          | '(SMC_0402R_C)'                        | 'RES,2.49K,1%,0.063W,0402'                                                              | ''        
 'G152-10119-01' | '24.9OHM'    | '0.5%'       = 'SMC_0402R_H016'     | '(SMC_0402R_C_H016)'                   | 'RES,24.9,0.5%,0.0625W,0402'                                                            | ''        
 'G152-10118-01' | '1KOHM'      | '0.5%'       = 'SMC_0402R_H016'     | '(SMC_0402R_C_H016)'                   | 'RES,1K,0.5%,0.0625W,0402'                                                              | ''        
 'G155-08200-01' | '820OHM'     | '1%'         = 'SMC_0402R_H016'     | '(SMC_0402R_C_H016)'                   | 'RES,820,1%,0.063W,0402'                                                                | ''        
 'G155-02263-01' | '226KOHM'    | '1%'         = 'SMC_0402R_H016'     | '(SMC_0402R_C_H016)'                   | 'RES,226K,1%,0.063W,0402'                                                               | ''        
 'G155-01653-01' | '165KOHM'    | '1%'         = 'SMC_0402R_H016'     | '(SMC_0402R_C_H016)'                   | 'RES,165K,1%,0.063W,0402'                                                               | ''        
 'G155-04321-01' | '4.32KOHM'   | '1%'         = 'SMC_0402R_H016'     | '(SMC_0402R_C_H016)'                   | 'RES,4.32K,1%,0.063W,0402'                                                              | ''        
 'G155-036R0-01' | '36OHM'      | '1%'         = 'SMC_0402R'          | '(SMC_0402R_C)'                        | 'RES,36,1%,0.0625W,0402'                                                                | ''        
 'G155-01543-01' | '154KOHM'    | '1%'         = 'SMC_0402R_H016'     | '(SMC_0402R_C_H016)'                   | 'RES,154K,1%,0.063W,0402'                                                               | ''        
 'G155-01403-01' | '140KOHM'    | '1%'         = 'SMC_0402R_H016'     | '(SMC_0402R_C_H016)'                   | 'RES,140K,1%,0.063W,0402'                                                               | ''        
 'G156-03832-01' | '38.3KOHM'   | '1%'         = 'SMC_0603R_H022'     | '(SMC_0603R_H022)'                     | 'RES,38.3K,1%,0.1W,0603'                                                                | ''        
 'G156-13001-01' | '3KOHM'      | '1%'         = 'SMC_0603R_H022'     | '(SMC_0603R_H022)'                     | 'RES, 3K, 1%, 0.1W, 0603'                                                               | ''        
 'G155-04531-01' | '4.53KOHM'   | '1%'         = 'SMC_0402R_H016'     | '(SMC_0402R_C_H016,C0402_BGA)'         | 'RES,4.53K,1%,0.063W,0402'                                                              | ''        
 'G152-10251-01' | '4.42KOHM'   | '1%'         = 'SMC_1206R_H026'     | '(SMC_1206R_H026)'                     | 'RES,4.42KOHM,1%,0.25W,1206'                                                            | ''        
 'G155-03012-01' | '30.1KOHM'   | '1%'         = 'SMC_0402R_H016'     | '(SMC_0402R_C_H016)'                   | 'RES,30.1K,1%,0.063W,0402'                                                              | ''        
 'G155-06800-01' | '680OHM'     | '1%'         = 'SMC_0402R_H016'     | '(SMC_0402R_C_H016)'                   | 'RES,680,1%,0.063W,0402'                                                                | ''        
 'G156-03000-01' | '300OHM'     | '1%'         = 'SMC_0603R_H022'     | '(SMC_0603R_H022)'                     | 'RES,300,1%,0.1W,0603'                                                                  | ''        
 'G155-01330-01' | '133OHM'     | '1%'         = 'SMC_0402R_H016'     | '(SMC_0402R_C_H016)'                   | 'RES,133,1%,0.063W,0402'                                                                | ''        
 'G155-051R1-01' | '51.1OHM'    | '1%'         = 'SMC_0402R'          | '(SMC_0402R_C)'                        | 'RES,51.1,1%,0.0625W,0402'                                                              | ''        
 'G155-01R00-01' | '1.0OHM'     | '1%'         = 'SMC_0402R'          | '(SMC_0402R_C)'                        | 'RES,1.0,1%,0.063W,0402'                                                                | 'NFND'    
 'G155-04701-01' | '4.7KOHM'    | '1%'         = 'SMC_0402R'          | '(SMC_0402R_C)'                        | 'RES,4.7K,1%,0.063W,0402'                                                               | 'NFND'    
 'G155-04991-01' | '4.99KOHM'   | '1%'         = 'SMC_0402R'          | '(SMC_0402R_C)'                        | 'RES,4.99K,1%,0.063W,0402'                                                              | 'NFND'    
 'G155-049R9-01' | '49.9OHM'    | '1%'         = 'SMC_0402R'          | '(SMC_0402R_C)'                        | 'RES,49.9,1%,0.063W,0402'                                                               | 'NFND'    
 'G155-082R5-01' | '82.5OHM'    | '1%'         = 'SMC_0402R_H016'     | '(SMC_0402R_C_H016)'                   | 'RES,82.5,1%,0.063W,0402'                                                               | ''        
 'G155-01241-01' | '1.24KOHM'   | '1%'         = 'SMC_0402R_H016'     | '(SMC_0402R_C_H016)'                   | 'RES,1.24K,1%,0.063W,0402'                                                              | ''        
 'G155-01500-01' | '150OHM'     | '1%'         = 'SMC_0402R_H016'     | '(SMC_0402R_C_H016)'                   | 'RES,150,1%,0.063W,0402'                                                                | 'NFND'    
 'G155-01004-01' | '1MOHM'      | '1%'         = 'SMC_0402R'          | '(SMC_0402R_C)'                        | 'RES,1M,1%,0.063W,0402'                                                                 | 'NFND'    
 'G155-033R0-01' | '33OHM'      | '1%'         = 'SMC_0402R_H016'     | '(SMC_0402R_C_H016)'                   | 'RES,33,1%,0.063W,0402'                                                                 | 'NFND'    
 'G155-09760-01' | '976OHM'     | '1%'         = 'SMC_0402R_H016'     | '(SMC_0402R_C_H016)'                   | 'RES,976,1%,0.063W,0402'                                                                | ''        
 'A155-075R0-DL' | '75OHM'      | '1%'         = 'SMC_0402R_H016'     | '(SMC_0402R_C_H016)'                   | 'RES,75OHM,1%,0.063W,0402'                                                              | ''        
 'A155-02000-DL' | '200OHM'     | '1%'         = 'SMC_0402R_H016'     | '(SMC_0402R_C_H016)'                   | 'RES,200OHM,1%,0.063W,0402'                                                             | ''        
 'A155-01201-DL' | '1.2KOHM'    | '1%'         = 'SMC_0402R_H016'     | '(SMC_0402R_C_H016)'                   | 'RES,1.2KOHM,1%,1/16W,0402'                                                             | ''        
 'A156-01871-DL' | '1.87KOHM'   | '1%'         = 'SMC_0603R_H024'     | '(SMC_0603R_H024)'                     | 'RES,1.87KOHM,1%,1/10W,0603'                                                            | ''        
 'A155-02701-DL' | '2.7KOHM'    | '1%'         = 'SMC_0402R_H016'     | '(SMC_0402R_C_H016)'                   | 'RES,2.7KOHM,1%,1/16W,0402'                                                             | ''        
 'A155-03301-DL' | '3.3KOHM'    | '1%'         = 'SMC_0402R_H016'     | '(SMC_0402R_C_H016)'                   | 'RES,3.3KOHM,1%,1/16,0402'                                                              | ''        
 'A155-03401-DL' | '3.4KOHM'    | '1%'         = 'SMC_0402R_H016'     | '(SMC_0402R_C_H016)'                   | 'RES,3.4KOHM,1%,1/16W,0402'                                                             | ''        
 'A155-01002-DL' | '10KOHM'     | '1%'         = 'SMC_0402R_H016'     | '(SMC_0402R_C_H016)'                   | 'RES,10KOHM,1%,1/16W,0402'                                                              | ''        
 'A155-03012-DL' | '30.1KOHM'   | '1%'         = 'SMC_0402R_H016'     | '(SMC_0402R_C_H016)'                   | 'RES,30.1KOHM,1%,1/16W,0402'                                                            | ''        
 'A155-05232-DL' | '52.3KOHM'   | '1%'         = 'SMC_0402R_H016'     | '(SMC_0402R_C_H016)'                   | 'RES,52.3KOHM,1%,1/16W,0402'                                                            | ''        
 'A155-04701-DL' | '4.7KOHM'    | '1%'         = 'SMC_0402R_H016'     | '(SMC_0402R_C_H016)'                   | 'RES,4.7KOHM,1%,1/16W,0402'                                                             | ''        
 'A155-02371-DL' | '2.37KOHM'   | '1%'         = 'SMC_0402R_H016'     | '(SMC_0402R_C_H016)'                   | 'RES,2.37KOHM,1%,1/16W,0402'                                                            | ''        
 'A155-01690-DL' | '169OHM'     | '1%'         = 'SMC_0402R_H016'     | '(SMC_0402R_C_H016)'                   | 'RES,169OHM,1%,1/16W,0402'                                                              | ''        
 'A155-01000-DL' | '100OHM'     | '1%'         = 'SMC_0402R_H016'     | '(SMC_0402R_C_H016)'                   | 'RES,100OHM,1%,1/16W,0402'                                                              | ''        
 'A156-01242-DL' | '12.4KOHM'   | '1%'         = 'SMC_0603R_H024'     | '(SMC_0603R_H024)'                     | 'RES,12.4KOHM,1%,1/10W,0603'                                                            | ''        
 'A155-05101-DL' | '5.1KOHM'    | '1%'         = 'SMC_0402R_H016'     | '(SMC_0402R_C_H016)'                   | 'RES,5.1KOHM,1%,1/16W,0402'                                                             | ''        
 'A156-02401-DL' | '2.4KOHM'    | '1%'         = 'SMC_0603R_H024'     | '(SMC_0603R_H024)'                     | 'RES,2.4KOHM,1%,1/10W,0603'                                                             | ''        
 'A155-03001-DL' | '3KOHM'      | '1%'         = 'SMC_0402R_H016'     | '(SMC_0402R_C_H016)'                   | 'RES,3KOHM,1%,0.063W,0402'                                                              | ''        
 'A155-02401-DL' | '2.4KOHM'    | '1%'         = 'SMC_0402R_H016'     | '(SMC_0402R_C_H016)'                   | 'RES,2.4KOHM,1%,0.063W,0402'                                                            | ''        
 'A152-02201-DL' | '2.2KOHM'    | '0.5%'       = 'SMC_0603R_H024'     | '(SMC_0603R_H024)'                     | 'RES,2.2KOHM,0.5%,0.1W,0603'                                                            | ''        
 'A152-03201-DL' | '3.2KOHM'    | '0.5%'       = 'SMC_0402R_H016'     | '(SMC_0402R_C_H016)'                   | 'RES,3.2KOHM,0.5%,1/16W,0402'                                                           | ''        
 'G156-01620-01' | '162OHM'     | '1%'         = 'SMC_0603R'          | '(SMC_0603R)'                          | 'RES,162,1%,0.1W,0603'                                                                  | ''        
 'G155-01502-01' | '15KOHM'     | '1%'         = 'SMC_0402R'          | '(SMC_0402R_C)'                        | 'RES,15K,1%,0.063W,0402'                                                                | 'NFND'    
 'G156-01003-01' | '100KOHM'    | '1%'         = 'SMC_0603R'          | '(SMC_0603R)'                          | 'RES,100K,1%,0.1W,0603'                                                                 | ''        
 'G155-02320-01' | '232OHM'     | '1%'         = 'SMC_0402R_H016'     | '(SMC_0402R_C_H016)'                   | 'RES,232,1%,0.063W,0402'                                                                | ''        
 'G156-039R2-01' | '39.2OHM'    | '1%'         = 'SMC_0603R_H022'     | '(SMC_0603R_H022)'                     | 'RES,39.2,1%,0.1W,0603'                                                                 | ''        
 'G156-00511-05' | '510OHM'     | '5%'         = 'SMC_0603R_H022'     | '(SMC_0603R_H022)'                     | 'RES,510,5%,0.1W,0603'                                                                  | ''        
 'G155-07502-01' | '75KOHM'     | '1%'         = 'SMC_0402R_H016'     | '(SMC_0402R_C_H016)'                   | 'RES,75K,1%,0.0625W,0402'                                                               | ''        
 'G156-01202-01' | '12KOHM'     | '1%'         = 'SMC_0603R_H024'     | '(SMC_0603R_H024)'                     | 'RES,12K,1%,0.1W,0603'                                                                  | ''        
 'G156-05102-01' | '51KOHM'     | '1%'         = 'SMC_0603R_H024'     | '(SMC_0603R_H024)'                     | 'RES,51K,1%,0.1W,0603'                                                                  | ''        
 'G156-04702-01' | '47KOHM'     | '1%'         = 'SMC_0603R_H024'     | '(SMC_0603R_H024)'                     | 'RES,47K,1%,0.1W,0603'                                                                  | ''        
 'G156-04700-01' | '470OHM'     | '1%'         = 'SMC_0603R_H024'     | '(SMC_0603R_H024)'                     | 'RES,470OHM,1%,0.1W,0603'                                                               | ''        
 'G156-002R7-05' | '2.7OHM'     | '5%'         = 'SMC_0603R_H024'     | '(SMC_0603R_H024)'                     | 'RES,2.7OHM,5%,0.1W,0603'                                                               | ''        
 'G156-00152-05' | '1.5KOHM'    | '5%'         = 'SMC_0603R_H024'     | '(SMC_0603R_H024)'                     | 'RES,1.5K,5%,0.1W,0603'                                                                 | ''        
 'G156-03002-01' | '30KOHM'     | '1%'         = 'SMC_0603R_H024'     | '(SMC_0603R_H024)'                     | 'RES,30K,1%,0.1W,0603'                                                                  | ''        
 'G156-00241-05' | '240OHM'     | '5%'         = 'SMC_0603R_H024'     | '(SMC_0603R_H024)'                     | 'RES,240OHM,5%,0.1W,0603'                                                               | ''        
 'G156-00330-05' | '33OHM'      | '5%'         = 'SMC_0603R_H024'     | '(SMC_0603R_H024)'                     | 'RES,33OHM,5%,0.1W,0603'                                                                | ''        
 'G156-02371-01' | '2.37KOHM'   | '1%'         = 'SMC_0603R_H024'     | '(SMC_0603R_H024)'                     | 'RES,2.37K,1%,0.1W,0603'                                                                | ''        
 'G156-01200-01' | '120OHM'     | '1%'         = 'SMC_0603R_H024'     | '(SMC_0603R_H024)'                     | 'RES,120OHM,1%,0.1W,0603'                                                               | ''        
 'G158-00102-05' | '1KOHM'      | '5%'         = 'SMC_1206R_H030'     | '(SMC_1206R_H030)'                     | 'RES,1K,5%,0.25W,1206'                                                                  | ''        
 'G156-00560-05' | '56OHM'      | '5%'         = 'SMC_0603R_H024'     | '(SMC_0603R_H024)'                     | 'RES,56OHM,5%,0.1W,0603'                                                                | ''        
 'G156-082R0-01' | '82OHM'      | '1%'         = 'SMC_0603R_H024'     | '(SMC_0603R_H024)'                     | 'RES,82OHM,1%,0.1W,0603'                                                                | ''        
 'G157-03602-01' | '36KOHM'     | '1%'         = 'SMC_0805R_H026'     | '(SMC_0805R_H026)'                     | 'RES,36K,1%,0.125W,0805'                                                                | ''        
 'G158-01203-01' | '120KOHM'    | '1%'         = 'SMC_1206R_H030'     | '(SMC_1206R_H030)'                     | 'RES,120K,1%,0.25W,1206'                                                                | ''        
 'G157-00100-05' | '10OHM'      | '5%'         = 'SMC_0805R_H026'     | '(SMC_0805R_H026)'                     | 'RES,10OHM,5%,0.125W,0805'                                                              | ''        
 'G158-01003-01' | '100KOHM'    | '1%'         = 'SMC_1206R_H030'     | '(SMC_1206R_H030)'                     | 'RES,100K,1%,0.25W,1206'                                                                | ''        
 'G156-00122-05' | '1.2KOHM'    | '5%'         = 'SMC_0603R_H024'     | '(SMC_0603R_H024)'                     | 'RES,1.2K,5%,0.1W,0603'                                                                 | ''        
 'G158-00106-05' | '10MOHM'     | '5%'         = 'SMC_1206R_H030'     | '(SMC_1206R_H030)'                     | 'RES,10M,5%,0.25W,1206'                                                                 | ''        
 'G157-01001-01' | '1KOHM'      | '1%'         = 'SMC_0805R_H026'     | '(SMC_0805R_H026)'                     | 'RES,1K,1%,0.125W,0805'                                                                 | ''        
 'G157-02003-01' | '200KOHM'    | '1%'         = 'SMC_0805R_H026'     | '(SMC_0805R_H026)'                     | 'RES,200K,1%,0.125W,0805'                                                               | ''        
 'G158-00681-05' | '680OHM'     | '5%'         = 'SMC_1206R_H030'     | '(SMC_1206R_H030)'                     | 'RES,680OHM,5%,0.25W,1206'                                                              | ''        
 'G156-00220-05' | '22OHM'      | '5%'         = 'SMC_0603R_H024'     | '(SMC_0603R_H024)'                     | 'RES,22OHM,5%,0.1W,0603'                                                                | ''        
 'G156-03301-01' | '3.3K'       | '1%'         = 'SMC_0603R_H024'     | '(SMC_0603R_H024)'                     | 'RES,3.3K,1%,0.1W,0603'                                                                 | ''        
 'G156-05100-01' | '510OHM'     | '1%'         = 'SMC_0603R_H024'     | '(SMC_0603R_H024)'                     | 'RES,510OHM,1%,0.1W,0603'                                                               | ''        
 'G156-03300-01' | '330OHM'     | '1%'         = 'SMC_0603R_H024'     | '(SMC_0603R_H024)'                     | 'RES,330OHM,1%,0.1W,0603'                                                               | ''        
 'G156-01650-01' | '165OHM'     | '1%'         = 'SMC_0603R_H024'     | '(SMC_0603R_H024)'                     | 'RES,165OHM,1%,0.1W,0603'                                                               | ''        
 'G156-02200-01' | '220OHM'     | '1%'         = 'SMC_0603R_H024'     | '(SMC_0603R_H024)'                     | 'RES,220OHM,1%,0.1W,0603'                                                               | ''        
 'G156-09101-01' | '9.1KOHM'    | '1%'         = 'SMC_0603R_H024'     | '(SMC_0603R_H024)'                     | 'RES,9.1K,1%,0.1W,0603'                                                                 | ''        
 'G157-00472-05' | '4.7KOHM'    | '5%'         = 'SMC_0805R_H026'     | '(SMC_0805R_H026)'                     | 'RES,4.7K,5%,0.125W,0805'                                                               | ''        
 'G156-00620-05' | '62OHM'      | '5%'         = 'SMC_0603R_H024'     | '(SMC_0603R_H024)'                     | 'RES,62OHM,5%,0.1W,0603'                                                                | ''        
 'G155-039R2-01' | '39.2OHM'    | '1%'         = 'SMC_0402R_H016'     | '(SMC_0402R_C_H016)'                   | 'RES,39.2,1%,0.063W,0402'                                                               | ''        
 'G156-075R0-01' | '75.0OHM'    | '1%'         = 'SMC_0603R'          | '(SMC_0603R)'                          | 'RES,75.0,1%,0.1W,0603'                                                                 | ''        
 'G155-05100-01' | '510OHM'     | '1%'         = 'SMC_0402R_H016'     | '(SMC_0402R_C_H016)'                   | 'RES,510OHM,1%,0.0625W,0402'                                                            | ''        
 'G156-000R0-05' | '0OHM'       | '5%'         = 'SMC_0603R'          | '(SMC_0603R)'                          | 'RES,0,5%,0.1W,0603'                                                                    | 'NFND'    
 'G156-06041-01' | '6.04K'      | '1%'         = 'SMC_0603R'          | '(SMC_0603R)'                          | 'RES,6.04K,1%,0.1W,0603'                                                                | ''        
 'G152-10261-01' | '0.01OHM'    | '5%'         = 'SMC_2010R_H026'     | '(SMC_2010R_H026)'                     | 'RES,0.01OHM,5%,0.75W,2010'                                                             | ''        
 'G155-023R2-01' | '23.2OHM'    | '1%'         = 'SMC_0402R_H016'     | '(SMC_0402R_C_H016)'                   | 'RES,23.2,1%,0.063W,0402'                                                               | ''        
 'G155-029R4-01' | '29.4OHM'    | '1%'         = 'SMC_0402R_H016'     | '(SMC_0402R_C_H016)'                   | 'RES,29.4,1%,0.063W,0402'                                                               | ''        
 'G155-047R5-01' | '47.5OHM'    | '1%'         = 'SMC_0402R_H016'     | '(SMC_0402R_C_H016)'                   | 'RES,47.5,1%,0.063W,0402'                                                               | ''        
 'G157-03000-01' | '300OHM'     | '1%'         = 'SMC_0805R_H028'     | '(SMC_0805R_H028)'                     | 'RES,300OHM,1%,0.125W,0805'                                                             | ''        
 'G155-04021-01' | '4.02K'      | '1%'         = 'SMC_0402R'          | '(SMC_0402R_C)'                        | 'RES,4.02K,1%,0.063W,0402'                                                              | ''        
 'G155-00R51-01' | '0.51OHM'    | '1%'         = 'SMC_0402R_H016'     | '(SMC_0402R_C_H016)'                   | 'RES,0.51,1%,0.063W,0402'                                                               | ''        
 'A155-01151-DL' | '1.15K'      | '1%'         = 'SMC_0402R_H016'     | '(SMC_0402R_C_H016)'                   | 'RES,1.15K,1%,0.063W,0402'                                                              | ''        
 'A155-03002-DL' | '30K'        | '1%'         = 'SMC_0402R_H016'     | '(SMC_0402R_C_H016)'                   | 'RES,30K,1%,0.0625W,0402'                                                               | ''        
 'A152-01151-DL' | '1.15K'      | '0.5%'       = 'SMC_0402R_H016'     | '(SMC_0402R_C_H016)'                   | 'RES,1.15K,0.5%,0.063W,0402'                                                            | ''        
 'A156-01002-DL' | '10K'        | '1%'         = 'SMC_0603R_H024'     | '(SMC_0603R_H024)'                     | 'RES,10K,1%,0.1W,0603'                                                                  | ''        
 'A155-03921-DL' | '3.92K'      | '1%'         = 'SMC_0402R_H016'     | '(SMC_0402R_C_H016)'                   | 'RES,3.92K,1%,0.063W,0402'                                                              | ''        
 'A155-01152-DL' | '11.5KOHM'   | '1%'         = 'SMC_0402R_H016'     | '(SMC_0402R_C_H016)'                   | 'RES,11.5KOHM,1%,0.063W,0402'                                                           | ''        
 'A155-00100-DL' | '10OHM'      | '1%'         = 'SMC_0402R_H016'     | '(SMC_0402R_C_H016)'                   | 'RES,10,1%,0.063W,0402'                                                                 | ''        
 'A155-06202-DL' | '62KOHM'     | '1%'         = 'SMC_0402R_H016'     | '(SMC_0402R_C_H016)'                   | 'RES,62K,1%,0.063W,0402'                                                                | ''        
 'A155-02002-DL' | '20KOHM'     | '1%'         = 'SMC_0402R_H016'     | '(SMC_0402R_C_H016)'                   | 'RES,20K,1%,0.063W,0402'                                                                | ''        
 'A152-03012-DL' | '30.1KOHM'   | '0.5%'       = 'SMC_0402R_H016'     | '(SMC_0402R_C_H016)'                   | 'RES,30.1K,0.5%,0.063W,0402'                                                            | ''        
 'A152-01002-DL' | '10KOHM'     | '0.5%'       = 'SMC_0402R_H016'     | '(SMC_0402R_C_H016)'                   | 'RES,10K,0.5%,0.063W,0402'                                                              | ''        
 'A152-02001-DL' | '2KOHM'      | '0.5%'       = 'SMC_0402R_H016'     | '(SMC_0402R_C_H016)'                   | 'RES,2KOHM,0.5%,0.063W,0402'                                                            | ''        
 'A152-03001-DL' | '3KOHM'      | '0.5%'       = 'SMC_0402R_H016'     | '(SMC_0402R_C_H016)'                   | 'RES,3KOHM,0.5%,0.063W,0402'                                                            | ''        
 'G155-01270-01' | '127OHM'     | '1%'         = 'SMC_0402R_H016'     | '(SMC_0402R_C_H016)'                   | 'RES,127,1%,0.063W,0402'                                                                | ''        
 'G152-10266-01' | '8.76K'      | '0.1%'       = 'SMC_0603R_H024'     | '(SMC_0603R_H024)'                     | 'RES,8.76K,0.1%,0.063W,0603'                                                            | ''        
 'G155-02200-01' | '220OHM'     | '1%'         = 'SMC_0402R'          | '(SMC_0402R_C)'                        | 'RES,220,1%,0.063W,0402'                                                                | ''        
 'G156-04991-01' | '4.99K'      | '1%'         = 'SMC_0603R'          | '(SMC_0603R)'                          | 'RES,4.99K,1%,0.1W,0603'                                                                | ''        
 'A155-06191-DL' | '6.19K'      | '1%'         = 'SMC_0402R_H016'     | '(SMC_0402R_C_H016)'                   | 'RES,6.19K,1%,0.063W,0402'                                                              | ''        
 'A155-01102-DL' | '11.0K'      | '1%'         = 'SMC_0402R_H016'     | '(SMC_0402R_C_H016)'                   | 'RES,11.0K,1%,0.063W,0402'                                                              | ''        
 'A155-02101-DL' | '2.1K'       | '1%'         = 'SMC_0402R_H016'     | '(SMC_0402R_C_H016)'                   | 'RES,2.1K,1%,0.063W,0402'                                                               | ''        
 'G155-02000-01' | '200OHM'     | '1%'         = 'SMC_0402R_H016'     | '(SMC_0402R_C_H016)'                   | 'RES,200,1%,0.063W,0402'                                                                | 'NFND'    
 'G155-022R0-01' | '22OHM'      | '1%'         = 'SMC_0402R_H016'     | '(SMC_0402R_C_H016)'                   | 'RES,22,1%,0.0625W,0402'                                                                | 'NFND'    
 'G155-04750-01' | '475OHM'     | '1%'         = 'SMC_0402R'          | '(SMC_0402R_C)'                        | 'RES,475,1%,0.063W,0402'                                                                | ''        
 'G155-05901-01' | '5.9K'       | '1%'         = 'SMC_0402R_H016'     | '(SMC_0402R_C_H016)'                   | 'RES,5.9K,1%,0.063W,0402'                                                               | ''        
 'G155-02740-01' | '274OHM'     | '1%'         = 'SMC_0402R_H016'     | '(SMC_0402R_C_H016)'                   | 'RES,274,1%,0.063W,0402'                                                                | ''        
 'G156-02431-01' | '2.43K'      | '1%'         = 'SMC_0603R_H022'     | '(SMC_0603R_H022)'                     | 'RES,2.43K,1%,0.1W,0603'                                                                | ''        
 'G156-02002-01' | '20K'        | '1%'         = 'SMC_0603R'          | '(SMC_0603R)'                          | 'RES,20K,1%,0.1W,0603'                                                                  | ''        
 'G156-01800-01' | '180OHM'     | '1%'         = 'SMC_0603R_H022'     | '(SMC_0603R_H022)'                     | 'RES,180,1%,0.1W,0603'                                                                  | ''        
 'G156-02702-01' | '27.0K'      | '1%'         = 'SMC_0603R_H022'     | '(SMC_0603R_H022)'                     | 'RES,27.0K,1%,0.1W,0603'                                                                | ''        
 'G156-01401-01' | '1.40K'      | '1%'         = 'SMC_0603R_H022'     | '(SMC_0603R_H022)'                     | 'RES,1.40K,1%,0.1W,0603'                                                                | ''        
 'G156-02701-01' | '2.7KOHM'    | '1%'         = 'SMC_0603R_H022'     | '(SMC_0603R_H022)'                     | 'RES,2.7KOHM,1%,0.1W,0603'                                                              | ''        
 'G156-01820-01' | '182OHM'     | '1%'         = 'SMC_0603R_H022'     | '(SMC_0603R_H022)'                     | 'RES,182,1%,0.1W,0603'                                                                  | ''        
 'A152-22000-DL' | '2.2KOHM'    | '0.5%'       = 'SMC_0402R_H016'     | '(SMC_0402R_C_H016)'                   | 'RES,2.2KOHM,0.5%,1/16W,0402'                                                           | ''        
 'A155-06651-DL' | '6.65K'      | '1%'         = 'SMC_0402R_H016'     | '(SMC_0402R_C_H016)'                   | 'RES,6.65K,1%,0.063W,0402'                                                              | ''        
 'A155-022R0-DL' | '22OHM'      | '1%'         = 'SMC_0402R_H016'     | '(SMC_0402R_C_H016)'                   | 'RES,22,1%,0.0625W,0402'                                                                | ''        
 'A155-03832-DL' | '38.3K'      | '1%'         = 'SMC_0402R_H016'     | '(SMC_0402R_C_H016)'                   | 'RES,38.3K,1%,0.063W,0402'                                                              | ''        
 'G155-061R9-01' | '61.9OHM'    | '1%'         = 'SMC_0402R_H016'     | '(SMC_0402R_C_H016)'                   | 'RES,61.9,1%,0.063W,0402'                                                               | ''        
 'G155-02490-01' | '249OHM'     | '1%'         = 'SMC_0402R_H016'     | '(SMC_0402R_C_H016)'                   | 'RES,249,1%,0.063W,0402'                                                                | ''        
 'G152-10277-01' | '0.0003OHM'  | '1%'         = 'SMC_R_394X205'      | '(SMC_R_394X205)'                      | 'RES,0.0003OHM,1%,3W,3921'                                                              | ''        
 'G152-10278-01' | '0.0005OHM'  | '1%'         = 'SMC_R_394X205_H050' | '(SMC_R_394X205_H050)'                 | 'RES,0.0005OHM,1%,3W,3921'                                                              | ''        
 'A155-02400-DL' | '240OHM'     | '1%'         = 'SMC_0402R_H016'     | '(SMC_0402R_C_H016)'                   | 'RES,240,1%,0.063W,0402'                                                                | ''        
 'G155-04022-01' | '40.2K'      | '1%'         = 'SMC_0402R_H016'     | '(SMC_0402R_C_H016)'                   | 'RES,40.2K,1%,0.063W,0402'                                                              | ''        
 'G155-03321-01' | '3.32K'      | '1%'         = 'SMC_0402R'          | '(SMC_0402R_C)'                        | 'RES,3.32K,1%,0.063W,0402'                                                              | ''        
 'G155-05900-01' | '590OHM'     | '1%'         = 'SMC_0402R_H016'     | '(SMC_0402R_C_H016)'                   | 'RES,590,1%,0.063W,0402'                                                                | ''        
 'G155-07150-01' | '715OHM'     | '1%'         = 'SMC_0402R'          | '(SMC_0402R_C)'                        | 'RES,715,1%,0.063W,0402'                                                                | ''        
 'G155-07322-01' | '73.2K'      | '1%'         = 'SMC_0402R_H016'     | '(SMC_0402R_C_H016)'                   | 'RES,73.2K,1%,0.063W,0402'                                                              | ''        
 'G155-02212-01' | '22.1K'      | '1%'         = 'SMC_0402R'          | '(SMC_0402R_C)'                        | 'RES,22.1K,1%,0.063W,0402'                                                              | ''        
 'G155-01781-01' | '1.78K'      | '1%'         = 'SMC_0402R_H016'     | '(SMC_0402R_C_H016)'                   | 'RES,1.78K,1%,0.063W,0402'                                                              | ''        
 'G155-09532-01' | '95.3K'      | '1%'         = 'SMC_0402R_H016'     | '(SMC_0402R_C_H016)'                   | 'RES,95.3K,1%,0.0625W,0402'                                                             | ''        
 'G155-03571-01' | '3.57K'      | '1%'         = 'SMC_0402R'          | '(SMC_0402R_C)'                        | 'RES,3.57K,1%,0.063W,0402'                                                              | ''        
 'G156-02871-01' | '2.87K'      | '1%'         = 'SMC_0603R_H022'     | '(SMC_0603R_H022)'                     | 'RES,2.87K,1%,0.1W,0603'                                                                | ''        
 'G155-04220-01' | '422OHM'     | '1%'         = 'SMC_0402R_H016'     | '(SMC_0402R_C_H016)'                   | 'RES,422,1%,1/16W,0402'                                                                 | ''        
 'G155-01052-01' | '10.5K'      | '1%'         = 'SMC_0402R_H016'     | '(SMC_0402R_C_H016)'                   | 'RES,10.5K,1%,0.063W,0402'                                                              | ''        
 'G155-06811-01' | '6.81K'      | '1%'         = 'SMC_0402R'          | '(SMC_0402R_C)'                        | 'RES,6.81K,1%,0.063W,0402'                                                              | ''        
 'G155-02322-01' | '23.2K'      | '1%'         = 'SMC_0402R_H016'     | '(SMC_0402R_C_H016)'                   | 'RES,23.2K,1%,0.063W,0402'                                                              | ''        
 'G157-002R2-05' | '2.2OHM'     | '5%'         = 'SMC_0805R'          | '(SMC_0805R)'                          | 'RES,2.2,5%,0.125W,0805'                                                                | 'NFND'    
 'G155-02742-01' | '27.4K'      | '1%'         = 'SMC_0402R_H016'     | '(SMC_0402R_C_H016)'                   | 'RES,27.4K,1%,0.063W,0402'                                                              | ''        
 'G155-03831-01' | '3.83K'      | '1%'         = 'SMC_0402R_H016'     | '(SMC_0402R_C_H016)'                   | 'RES,3.83K,1%,0.063W,0402'                                                              | ''        
 'G155-05R11-01' | '5.11OHM'    | '1%'         = 'SMC_0402R_H016'     | '(SMC_0402R_C_H016)'                   | 'RES,5.11,1%,0.0625W,0402'                                                              | ''        
 'G155-01212-01' | '12.1K'      | '1%'         = 'SMC_0402R'          | '(SMC_0402R_C)'                        | 'RES,12.1K,1%,0.063W,0402'                                                              | ''        
 'G155-08870-01' | '887OHM'     | '1%'         = 'SMC_0402R_H016'     | '(SMC_0402R_C_H016)'                   | 'RES,887,1%,0.063W,0402'                                                                | ''        
 'G157-000R0-05' | '0OHM'       | '5%'         = 'SMC_0805R'          | '(SMC_0805R)'                          | 'RES,0,5%,0.125W,0805'                                                                  | 'NFND'    
 'G158-002R2-05' | '2.2OHM'     | '5%'         = 'SMC_R_1206'         | '(SMC_R_1206)'                         | 'RES,2.2,5%,0.25W,1206'                                                                 | ''        
 'G155-01601-01' | '1.6K'       | '1%'         = 'SMC_0402R_H016'     | '(SMC_0402R_C_H016)'                   | 'RES,1.6K,1%,0.0625W,0402'                                                              | ''        
 'G155-01151-01' | '1.15K'      | '1%'         = 'SMC_0402R'          | '(SMC_0402R_C)'                        | 'RES,1.15K,1%,0.063W,0402'                                                              | ''        
 'G155-06342-01' | '63.4K'      | '1%'         = 'SMC_0402R_H016'     | '(SMC_0402R_C_H016)'                   | 'RES,63.4K,1%,0.0625W,0402'                                                             | ''        
 'G155-02262-01' | '22.6K'      | '1%'         = 'SMC_0402R_H016'     | '(SMC_0402R_C_H016)'                   | 'RES,22.6K,1%,0.063W,0402'                                                              | ''        
 'G155-08871-01' | '8.87K'      | '1%'         = 'SMC_0402R'          | '(SMC_0402R_C)'                        | 'RES,8.87K,1%,0.063W,0402'                                                              | ''        
 'G155-05762-01' | '57.6K'      | '1%'         = 'SMC_0402R_H016'     | '(SMC_0402R_C_H016)'                   | 'RES,57.6K,1%,0.063W,0402'                                                              | ''        
 'G155-03402-01' | '34K'        | '1%'         = 'SMC_0402R_H016'     | '(SMC_0402R_C_H016)'                   | 'RES,34K,1%,0.063W,0402'                                                                | ''        
 'G155-04872-01' | '48.7K'      | '1%'         = 'SMC_0402R_H016'     | '(SMC_0402R_C_H016)'                   | 'RES,48.7K,1%,0.063W,0402'                                                              | ''        
 'G156-002R2-05' | '2.2OHM'     | '5%'         = 'SMC_0603R_H024'     | '(SMC_0603R_H024)'                     | 'RES,2.2,5%,0.1W,0603'                                                                  | 'NFND'    
 'G155-02372-01' | '23.7K'      | '1%'         = 'SMC_0402R_H016'     | '(SMC_0402R_C_H016)'                   | 'RES,23.7K,1%,0.0625W,0402'                                                             | ''        
 'G156-01001-01' | '1K'         | '1%'         = 'SMC_0603R'          | '(SMC_0603R)'                          | 'RES,1K,1%,0.1W,0603'                                                                   | 'NFND'    
 'G156-02741-01' | '2.74K'      | '1%'         = 'SMC_0603R'          | '(SMC_0603R)'                          | 'RES,2.74K,1%,0.1W,0603'                                                                | ''        
 'G156-01R00-01' | '1.0OHM'     | '1%'         = 'SMC_0603R'          | '(SMC_0603R)'                          | 'RES,1.0,1%,0.1W,0603'                                                                  | ''        
 'G155-04R64-01' | '4.64OHM'    | '1%'         = 'SMC_0402R_H016'     | '(SMC_0402R_C_H016)'                   | 'RES,4.64OHM,1%,0.0625,0402'                                                            | ''        
 'G156-03481-01' | '3.48K'      | '1%'         = 'SMC_0603R_H022'     | '(SMC_0603R_H022)'                     | 'RES,3.48K,1%,0.1W,0603'                                                                | 'NFND'    
 'G155-022R6-01' | '22.6OHM'    | '1%'         = 'SMC_0402R'          | '(SMC_0402R_C)'                        | 'RES,22.6,1%,0.063W,0402'                                                               | ''        
 'G155-01022-01' | '10.2K'      | '1%'         = 'SMC_0402R_H016'     | '(SMC_0402R_C_H016)'                   | 'RES,10.2K,1%,0.063W,0402'                                                              | ''        
 'G155-02672-01' | '26.7K'      | '1%'         = 'SMC_0402R_H016'     | '(SMC_0402R_C_H016)'                   | 'RES,26.7K,1%,0.063W,0402'                                                              | ''        
 'G152-10281-01' | '130OHM'     | '1%'         = 'SMC_1210R_H028'     | '(SMC_1210R_H028)'                     | 'RES,130OHM,1%,0.5W,1210'                                                               | ''        
 'G152-10282-01' | '170OHM'     | '1%'         = 'SMC_1210R_H028'     | '(SMC_1210R_H028)'                     | 'RES,170OHM,1%,0.5W,1210'                                                               | ''        
 'G152-10284-01' | '169OHM'     | '1%'         = 'SMC_1210R_H028'     | '(SMC_1210R_H028)'                     | 'RES,169OHM,1%,0.5W,1210'                                                               | ''        
 'G155-01910-01' | '191OHM'     | '1%'         = 'SMC_0402R_H016'     | '(SMC_0402R_C_H016)'                   | 'RES,191,1%,0.063W,0402'                                                                | ''        
 'G155-03922-01' | '39.2K'      | '1%'         = 'SMC_0402R_H016'     | '(SMC_0402R_C_H016)'                   | 'RES,39.2K,1%,0.063W,0402'                                                              | ''        
 'G156-01212-01' | '12.1K'      | '1%'         = 'SMC_0603R'          | '(SMC_0603R)'                          | 'RES,12.1K,1%,0.1W,0603'                                                                | ''        
 'G155-060R4-01' | '60.4OHM'    | '1%'         = 'SMC_0402R_H016'     | '(SMC_0402R_C_H016)'                   | 'RES,60.4,1%,0.063W,0402'                                                               | ''        
 'G155-02743-01' | '274KOHM'    | '1%'         = 'SMC_0402R_H016'     | '(SMC_0402R_C_H016)'                   | 'RES,274K,1%,0.063W,0402'                                                               | ''        
 'G155-01303-01' | '130KOHM'    | '1%'         = 'SMC_0402R_H016'     | '(SMC_0402R_C_H016)'                   | 'RES,130K,1%,0.0625W,0402'                                                              | ''        
 'G155-01580-01' | '158OHM'     | '1%'         = 'SMC_0402R_H016'     | '(SMC_0402R_C_H016)'                   | 'RES,158,1%,0.063W,0402'                                                                | ''        
 'G155-01200-01' | '120OHM'     | '1%'         = 'SMC_0402R_H016'     | '(SMC_0402R_C_H016)'                   | 'RES,120,1%,0.063W,0402'                                                                | 'NFND'    
 'G155-08201-01' | '8.2KOHM'    | '1%'         = 'SMC_0402R_H016'     | '(SMC_0402R_C_H016)'                   | 'RES,8.2K,1%,0.063W,0402'                                                               | ''        
 'G155-040R2-01' | '40.2OHM'    | '1%'         = 'SMC_0402R_H016'     | '(SMC_0402R_C_H016)'                   | 'RES,40.2,1%,0.063W,0402'                                                               | ''        
 'G155-04R99-01' | '4.99OHM'    | '1%'         = 'SMC_0402R_H016'     | '(SMC_0402R_C_H016)'                   | 'RES,4.99OHM,1%,0.063W,0402'                                                            | ''        
 'G156-028R0-01' | '28OHM'      | '1%'         = 'SMC_0603R_H022'     | '(SMC_0603R_H022)'                     | 'RES,28OHM,1%,0.1W,0603'                                                                | ''        
 'G152-10297-01' | '0.27OHM'    | '1%'         = 'SMC_0603R_H024'     | '(SMC_0603R_H024)'                     | 'RES,0.27OHM,1%,0.2W,0603'                                                              | ''        
 'G155-01182-01' | '11.8KOHM'   | '1%'         = 'SMC_0402R_H016'     | '(SMC_0402R_C_H016)'                   | 'RES,11.8K,1%,0.0625W,0402'                                                             | ''        
 'G152-10301-01' | '0.003OHM'   | '1%'         = 'SMC_R_394X205_H037' | '(SMC_R_394X205_H037)'                 | 'RES,0.003OHM,1%,3W,3921'                                                               | ''        
 'G152-10302-01' | '0.001OHM'   | '1%'         = 'SMC_R_394X205_H035' | '(SMC_R_394X205_H035)'                 | 'RES,0.001OHM,1%,3W,3921'                                                               | ''        
 'G155-01961-01' | '1.96KOHM'   | '1%'         = 'SMC_0402R_H016'     | '(SMC_0402R_C_H016)'                   | 'RES,1.96K,1%,0.063W,0402'                                                              | ''        
 'G155-02492-01' | '24.9KOHM'   | '1%'         = 'SMC_0402R_H016'     | '(SMC_0402R_C_H016)'                   | 'RES,24.9K,1%,0.063W,0402'                                                              | ''        
 'G156-00R10-01' | '0.1OHM'     | '1%'         = 'SMC_0603R_H022'     | '(SMC_0603R_H022)'                     | 'RES,0.1OHM,1%,0.1W,0603'                                                               | ''        
 'G152-10303-01' | '150OHM'     | '5%'         = 'SMC_1206R_H026'     | '(SMC_1206R_H026)'                     | 'RES,150,5%,2.4W,1206'                                                                  | ''        
 'G152-10304-01' | '360OHM'     | '1%'         = 'SMC_1206R_H026'     | '(SMC_1206R_H026)'                     | 'RES,360,1%,0.5W,1206'                                                                  | ''        
 'G155-042R2-01' | '42.2OHM'    | '1%'         = 'SMC_0402R_H016'     | '(SMC_0402R_C_H016)'                   | 'RES,42.2,1%,0.0625W,0402'                                                              | ''        
 'G155-00103-05' | '10KOHM'     | '5%'         = 'SMC_0402R_H016'     | '(SMC_0402R_C_H016)'                   | 'RES,TSB,10K,5%,0.063W,0402'                                                            | 'NFND'    
 'G157-00123-05' | '120KOHM'    | '5%'         = 'SMC_0805R_H024'     | '(SMC_0805R_H024)'                     | 'RES,120K,5%,0.125W,0805'                                                               | ''        
 'G155-027R4-01' | '27.4OHM'    | '1%'         = 'SMC_0402R_H016'     | '(SMC_0402R_C_H016)'                   | 'RES,27.4,1%,0.0625W,0402'                                                              | ''        
 'G155-090R9-01' | '90.9OHM'    | '1%'         = 'SMC_0402R_H016'     | '(SMC_0402R_C_H016)'                   | 'RES,90.9,1%,0.063W,0402'                                                               | ''        
 'G155-02R20-01' | '2.2OHM'     | '1%'         = 'SMC_0402R_H016'     | '(SMC_0402R_C_H016)'                   | 'RES,2.2,1%,0.0625W,0402'                                                               | ''        
 'G152-10276-01' | '249OHM'     | '0.1%'       = 'SMC_0402R_H016'     | '(SMC_0402R_C_H016)'                   | 'RES,249,0.1%,0.063W,0402'                                                              | ''        
 'G156-00100-05' | '10OHM'      | '5%'         = 'SMC_0603R'          | '(SMC_0603R)'                          | 'RES,10,5%,0.1W,0603'                                                                   | 'NFND'    
 'G156-0R510-01' | '0.51OHM'    | '1%'         = 'SMC_0603R_H022'     | '(SMC_0603R_H022)'                     | 'RES,0.51,1%,0.2W,0603'                                                                 | ''        
 'G156-08760-01' | '876OHM'     | '1%'         = 'SMC_0603R_H022'     | '(SMC_0603R_H022)'                     | 'RES,876,1%,0.1W,0603'                                                                  | ''        
 'G155-01602-01' | '16KOHM'     | '1%'         = 'SMC_0402R_H016'     | '(SMC_0402R_C_H016)'                   | 'RES,16K,1%,0.063W,0402'                                                                | ''        
 'G156-01200-05' | '120OHM'     | '5%'         = 'SMC_0603R_H022'     | '(SMC_0603R_H022)'                     | 'RES,120,5%,0.1W,0603'                                                                  | ''        
 'G152-10099-01' | '1KOHM'      | '5%'         = 'SMC_0402R_H016'     | '(SMC_0402R_C_H016)'                   | 'RES,1K,5%,0.125W,0402,HP'                                                              | ''        
 'G155-02671-01' | '2.67KOHM'   | '1%'         = 'SMC_0402R'          | '(SMC_0402R_C)'                        | 'RES,2.67K,1%,0.063W,0402'                                                              | ''        
 'G152-10164-01' | '0.001OHM'   | '1%'         = 'SMC_R_250X125_V2'   | '(SMC_R_250X125_V2)'                   | 'RES,0.001OHM,1%,1W,2512'                                                               | ''        
 'G155-03161-01' | '3.16KOHM'   | '1%'         = 'SMC_0402R_H016'     | '(SMC_0402R_C_H016)'                   | 'RES,3.16K,1%,0.063W,0402'                                                              | ''        
 'G155-04992-01' | '49.9KOHM'   | '1%'         = 'SMC_0402R_H016'     | '(SMC_0402R_C_H016)'                   | 'RES,49.9K,1%,0.0625W,0402'                                                             | ''        
 'G155-04752-01' | '47.5KOHM'   | '1%'         = 'SMC_0402R_H016'     | '(SMC_0402R_C_H016)'                   | 'RES,47.5K,1%,0.063W,0402'                                                              | ''        
 'G155-02211-01' | '2.21KOHM'   | '1%'         = 'SMC_0402R'          | '(SMC_0402R_C)'                        | 'RES,2.21K,1%,0.063W,0402'                                                              | ''        
 'G155-01050-01' | '105OHM'     | '1%'         = 'SMC_0402R_H016'     | '(SMC_0402R_C_H016)'                   | 'RES,105,1%,0.0625W,0402'                                                               | ''        
 'G155-01802-01' | '18KOHM'     | '1%'         = 'SMC_0402R_H016'     | '(SMC_0402R_C_H016)'                   | 'RES,18K,1%,0.063W,0402'                                                                | ''        
 'G154-03001-01' | '3KOHM'      | '1%'         = 'SMC_0201R'          | '(SMC_0201R_C)'                        | 'RES,3K,1%,0.05W,0201'                                                                  | ''        
 'G155-06810-01' | '681OHM'     | '1%'         = 'SMC_0402R_H016'     | '(SMC_0402R_C_H016)'                   | 'RES,681,1%,0.063W,0402'                                                                | ''        
 'G155-01801-01' | '1.8KOHM'    | '1%'         = 'SMC_0402R_H016'     | '(SMC_0402R_C_H016)'                   | 'RES,1.8K,1%,50V,0.0625W,0402'                                                          | ''        
 'G155-064R9-01' | '64.9OHM'    | '1%'         = 'SMC_0402R_H016'     | '(SMC_0402R_C_H016)'                   | 'RES,64.9,1%,0.0625W,0402'                                                              | ''        
 'G155-04120-01' | '412OHM'     | '1%'         = 'SMC_0402R_H016'     | '(SMC_0402R_C_H016)'                   | 'RES,412,1%,0.0625W,0402'                                                               | ''        
 'G152-10306-01' | '73.2OHM'    | '1%'         = 'SMC_0603R_H022'     | '(SMC_0603R_H022)'                     | 'RES,73.2OHM,1%,0.1W,0603'                                                              | ''        
 'G152-10279-01' | '100KOHM'    | '1%'         = 'SMC_1206R_H026'     | '(SMC_1206R_H026)'                     | 'RES,100KOHM,1%,0.5W,1206'                                                              | ''        
 'G158-04992-01' | '49.9KOHM'   | '1%'         = 'SMC_1206R_H028'     | '(SMC_1206R_H028)'                     | 'RES,49.9KOHM,1%,0.25W,1206'                                                            | ''        
 'G158-03322-01' | '33.2KOHM'   | '1%'         = 'SMC_1206R_H028'     | '(SMC_1206R_H028)'                     | 'RES,33.2KOHM,1%,0.25W,1206'                                                            | ''        
 'G156-04752-01' | '47.5KOHM'   | '1%'         = 'SMC_0603R_H022'     | '(SMC_0603R_H022)'                     | 'RES,47.5KOHM,1%,0.1W,0603'                                                             | ''        
 'G157-02001-01' | '2KOHM'      | '1%'         = 'SMC_0805R_H024'     | '(SMC_0805R_H024)'                     | 'RES,2KOHM,1%,0.125W,0805'                                                              | ''        
 'G157-04421-01' | '4.42KOHM'   | '1%'         = 'SMC_0805R_H024'     | '(SMC_0805R_H024)'                     | 'RES,4.42KOHM,1%,0.125W,0805'                                                           | ''        
 'G157-09092-01' | '90.9KOHM'   | '1%'         = 'SMC_0805R_H024'     | '(SMC_0805R_H024)'                     | 'RES,90.9KOHM,1%,0.125W,0805'                                                           | ''        
 'G157-02402-01' | '24KOHM'     | '1%'         = 'SMC_0805R_H024'     | '(SMC_0805R_H024)'                     | 'RES,24KOHM,1%,0.125W,0805'                                                             | ''        
 'G157-02403-01' | '240KOHM'    | '1%'         = 'SMC_0805R_H024'     | '(SMC_0805R_H024)'                     | 'RES,240KOHM,1%,0.125W,0805'                                                            | ''        
 'G158-0R002-01' | '0.002OHM'   | '1%'         = 'SMC_1206R_H035'     | '(SMC_1206R_H035)'                     | 'RES,0.002OHM,1%,1W,1206'                                                               | ''        
 'G152-10291-01' | '0OHM'       | '1%'         = 'SMC_1206R_H026'     | '(SMC_1206R_H026)'                     | 'RES,0OHM,1%,0.25W,1206'                                                                | ''        
 'G157-01002-01' | '10KOHM'     | '1%'         = 'SMC_0805R_H024'     | '(SMC_0805R_H024)'                     | 'RES,10KOHM,1%,0.125W,0805'                                                             | ''        
 'G152-03010-01' | '301OHM'     | '1%'         = 'SMC_2512R_H028'     | '(SMC_2512R_H028)'                     | 'RES,301OHM,1%,1W,2512'                                                                 | ''        
 'G158-022R1-01' | '22.1OHM'    | '1%'         = 'SMC_1206R_H028'     | '(SMC_1206R_H028)'                     | 'RES,22.1OHM,1%,0.25W,1206'                                                             | ''        
 'G152-02R00-01' | '2OHM'       | '1%'         = 'SMC_1210R_H024'     | '(SMC_1210R_H024)'                     | 'RES,2OHM,1%,0.5W,1210'                                                                 | ''        
 'G158-010R0-01' | '10OHM'      | '1%'         = 'SMC_1206R_H026'     | '(SMC_1206R_H026)'                     | 'RES,10OHM,1%,0.5W,1206'                                                                | ''        
 'G158-020R0-01' | '20OHM'      | '1%'         = 'SMC_1206R_H026'     | '(SMC_1206R_H026)'                     | 'RES,20OHM,1%,0.5W,1206'                                                                | ''        
 'G157-01000-01' | '100OHM'     | '1%'         = 'SMC_0805R_H026'     | '(SMC_0805R_H026)'                     | 'RES,100OHM,1%,0.25W,0805'                                                              | ''        
 'G158-022R0-01' | '22OHM'      | '1%'         = 'SMC_1206R_H026'     | '(SMC_1206R_H026)'                     | 'RES,22OHM,1%,0.5W,1206'                                                                | ''        
 'G155-02553-01' | '255KOHM'    | '1%'         = 'SMC_0402R_H016'     | '(SMC_0402R_C_H016)'                   | 'RES,255K,1%,0.063W,0402'                                                               | ''        
 'G152-10130-01' | '49.9KOHM'   | '0.1%'       = 'SMC_0402R_H014'     | '(SMC_0402R_C_H014)'                   | 'RES,49.9K,0.1%,0.0625W,0402'                                                           | 'NFND'    
 'G152-10133-01' | '475OHM'     | '0.1%'       = 'SMC_0402R_H014'     | '(SMC_0402R_C_H014)'                   | 'RES,475,0.1%,0.063W,0402'                                                              | ''        
 'G152-10132-01' | '158OHM'     | '0.1%'       = 'SMC_0603R_H018'     | '(SMC_0603R_H018)'                     | 'RES,158,0.1%,0.1W,0603'                                                                | ''        
 'G152-10134-01' | '73.2KOHM'   | '0.1%'       = 'SMC_0402R_H014'     | '(SMC_0402R_C_H014)'                   | 'RES,73.2K,0.1%,0.063W,0402'                                                            | ''        
 'G152-10141-01' | '3.57KOHM'   | '0.1%'       = 'SMC_0402R_H014'     | '(SMC_0402R_C_H014)'                   | 'RES,3.57K,0.1%,0.063W,0402'                                                            | ''        
 'G152-10295-01' | '90.9KOHM'   | '1%'         = 'SMC_1206R_H026'     | '(SMC_1206R_H026)'                     | 'RES,90.9K,1%,0.5W,1206'                                                                | ''        
 'G152-10139-01' | '22.1KOHM'   | '0.1%'       = 'SMC_0402R_H014'     | '(SMC_0402R_C_H014)'                   | 'RES,22.1K,0.1%,0.063W,0402'                                                            | 'NFND'    
 'G152-10125-01' | '20OHM'      | '0.1%'       = 'SMC_0402R_H014'     | '(SMC_0402R_C_H014)'                   | 'RES,20,0.1%,0.063W,0402'                                                               | ''        
 'G152-10172-01' | '2.61KOHM'   | '0.1%'       = 'SMC_0402R_H014'     | '(SMC_0402R_C_H014)'                   | 'RES,2.61K,0.1%,0.063W,0402'                                                            | ''        
 'G152-10171-01' | '1.0KOHM'    | '0.1%'       = 'SMC_0402R_H014'     | '(SMC_0402R_C_H014)'                   | 'RES,1.0K,0.1%,0.063W,0402'                                                             | 'NFND'    
 'G152-10246-01' | '3.4KOHM'    | '0.1%'       = 'SMC_0402R_H014'     | '(SMC_0402R_C_H014)'                   | 'RES,3.4K,0.1%,0.063W,0402'                                                             | ''        
 'G155-01130-01' | '113OHM'     | '1%'         = 'SMC_0402R_H014'     | '(SMC_0402R_C_H014)'                   | 'RES,113,1%,0.063W,0402'                                                                | ''        
 'G152-10307-01' | '200OHM'     | '1%'         = 'SMC_2512R_V5'       | '(SMC_2512R_V5)'                       | 'RES,200OHM,1%,3W,2512'                                                                 | ''        
 'G157-03903-01' | '390KOHM'    | '1%'         = 'SMC_0805R_H024'     | '(SMC_0805R_H024)'                     | 'RES,390K,1%,0.125W,0805'                                                               | ''        
 'G155-03652-01' | '36.5KOHM'   | '1%'         = 'SMC_0402R'          | '(SMC_0402R_C)'                        | 'RES,36.5K,1%,0.063W,0402'                                                              | ''        
 'G152-00014-01' | '9.1OHM'     | '5%'         = 'SMC_R_1210'         | '(SMC_R_1210)'                         | 'RES,9.1,5%,0.5W,1210'                                                                  | ''        
 'G158-0010R-05' | '10OHM'      | '5%'         = 'SMC_R_1206'         | '(SMC_R_1206)'                         | 'RES,10,5%,0.25W,1206'                                                                  | ''        
 'G152-10123-01' | '10KOHM'     | '0.1%'       = 'SMC_0402R_H014'     | '(SMC_0402R_C_H014)'                   | 'RES,10K,0.1%,0.063W,0402'                                                              | 'NFND'    
 'G155-04532-01' | '45.3KOHM'   | '1%'         = 'SMC_0402R_H016'     | '(SMC_0402R_C_H016)'                   | 'RES,45.3K,1%,0.063W,0402'                                                              | ''        
 'G155-032R4-01' | '32.4OHM'    | '1%'         = 'SMC_0402R_H016'     | '(SMC_0402R_C_H016)'                   | 'RES,32.4,1%,0.063W,0402'                                                               | ''        
 'G156-084R5-01' | '84.5OHM'    | '1%'         = 'SMC_0603R'          | '(SMC_0603R)'                          | 'RES,84.5,1%,0.1W,0603'                                                                 | ''        
 'G156-03322-01' | '33.2KOHM'   | '1%'         = 'SMC_0603R'          | '(SMC_0603R)'                          | 'RES,33.2K,1%,0.1W,0603'                                                                | ''        
 'G156-01872-01' | '18.7KOHM'   | '1%'         = 'SMC_0603R'          | '(SMC_0603R)'                          | 'RES,18.7K,1%,0.1W,0603'                                                                | ''        
 'G155-056R0-01' | '56OHM'      | '1%'         = 'SMC_0402R_H016'     | '(SMC_0402R_C_H016)'                   | 'RES,56,1%,0.0625W,0402'                                                                | ''        
 'G152-10310-01' | '1.78KOHM'   | '0.1%'       = 'SMC_0402R_H016'     | '(SMC_0402R_C_H016)'                   | 'RES,1.78K,0.1%,0.063W,0402'                                                            | ''        
 'G152-10311-01' | '1.91KOHM'   | '0.1%'       = 'SMC_0402R_H016'     | '(SMC_0402R_C_H016)'                   | 'RES,1.91K,0.1%,0.063W,0402'                                                            | ''        
 'G152-10312-01' | '2.94KOHM'   | '0.1%'       = 'SMC_0402R_H016'     | '(SMC_0402R_C_H016)'                   | 'RES,2.94K,0.1%,0.063W,0402'                                                            | ''        
 'G152-10313-01' | '976OHM'     | '0.1%'       = 'SMC_0402R_H016'     | '(SMC_0402R_C_H016)'                   | 'RES,976,0.1%,0.063W,0402'                                                              | ''        
 'G152-00009-01' | '0.001OHM'   | '0.1%'       = 'SMC_2512R_V2'       | '(SMC_2512R_V2)'                       | 'RES,0.001,1%,1W,2512'                                                                  | ''        
 'G152-10093-01' | '0.01OHM'    | '0.1%'       = 'SMC_2010R_H035'     | '(SMC_2010R_H035)'                     | 'RES,0.01,1%,0.5W,2010'                                                                 | ''        
 'G155-01332-01' | '13.3KOHM'   | '1%'         = 'SMC_0402R'          | '(SMC_0402R_C)'                        | 'RES,13.3K,1%,0.063W,0402'                                                              | ''        
 'G155-06341-01' | '6.34KOHM'   | '1%'         = 'SMC_0402R_H016'     | '(SMC_0402R_C_H016)'                   | 'RES,6.34K,1%,0.063W,0402'                                                              | ''        
 'G155-01692-01' | '16.9KOHM'   | '1%'         = 'SMC_0402R_H016'     | '(SMC_0402R_C_H016)'                   | 'RES,16.9K,1%,0.063W,0402'                                                              | ''        
 'G155-01211-01' | '1.21KOHM'   | '1%'         = 'SMC_0402R_H016'     | '(SMC_0402R_C_H016)'                   | 'RES,1.21K,1%,0.1W,0402'                                                                | ''        
 'G155-02670-01' | '267OHM'     | '1%'         = 'SMC_0402R'          | '(SMC_0402R_C)'                        | 'RES,267,1%,0.063W,0402'                                                                | ''        
 'G155-01244-01' | '1.24MOHM'   | '1%'         = 'SMC_0402R_H016'     | '(SMC_0402R_C_H016)'                   | 'RES,1.24M,1%,0.0625W,0402'                                                             | ''        
 'G155-04121-01' | '4.12KOHM'   | '1%'         = 'SMC_0402R_H016'     | '(SMC_0402R_C_H016)'                   | 'RES,4.12K,1%,0.063W,0402'                                                              | ''        
 'G157-001R0-05' | '1OHM'       | '5%'         = 'SMC_0805R_H024'     | '(SMC_0805R_H024)'                     | 'RES,1.0,5%,0.125W,0805'                                                                | ''        
 'G155-04700-01' | '470OHM'     | '1%'         = 'SMC_0402R_H016'     | '(SMC_0402R_C_H016)'                   | 'RES,470,1%,0.063W,0402'                                                                | ''        
 'G154-027R4-01' | '27.4OHM'    | '1%'         = 'SMC_0201R'          | '(SMC_0201R_C)'                        | 'RES, 27.4, 1%, 0.05W, 0201'                                                            | ''        
 'G154-042R2-01' | '42.2OHM'    | '1%'         = 'SMC_0201R'          | '(SMC_0201R_C)'                        | 'RES, 42.2, 1%, 0.05W, 0201'                                                            | ''        
 'G156-03741-01' | '3.74KOHM'   | '1%'         = 'SMC_0603R_H022'     | '(SMC_0603R_H022)'                     | 'RES,3.74K,1%,0.1W,0603'                                                                | ''        
 'G155-04533-01' | '453KOHM'    | '1%'         = 'SMC_0402R_H016'     | '(SMC_0402R_C_H016)'                   | 'RES,453K,1%,0.063W,0402'                                                               | ''        
 'G155-06652-01' | '66.5KOHM'   | '1%'         = 'SMC_0402R'          | '(SMC_0402R_C)'                        | 'RES, 66.5K,1%,0.063W,0402'                                                             | ''        
 'G155-02004-01' | '2MOHM'      | '1%'         = 'SMC_0402R_H016'     | '(SMC_0402R_C_H016)'                   | 'RES,2M,1%,0.0625W,0402'                                                                | ''        
 'G152-10314-01' | '0.00075OHM' | '1%'         = 'SMC_2512R_V2'       | '(SMC_2512R_V2)'                       | 'RES,0.00075OHM,1%,3W,400PPM/CEL,2512'                                                  | ''        
 'G156-01652-01' | '16.5KOHM'   | '1%'         = 'SMC_0603R_H022'     | '(SMC_0603R_H022)'                     | 'RES,16.5K,1%,0.1W,0603'                                                                | ''        
 'G155-05102-01' | '51KOHM'     | '1%'         = 'SMC_0402R_H016'     | '(SMC_0402R_C_H016)'                   | 'RES,51K,1%,0.0625W,0402'                                                               | ''        
 'G155-06981-01' | '6.98KOHM'   | '1%'         = 'SMC_0402R_H016'     | '(SMC_0402R_C_H016)'                   | 'RES,6.98K,1%,0.063W,0402'                                                              | ''        
 'G155-01541-01' | '1.54KOHM'   | '1%'         = 'SMC_0402R_H016'     | '(SMC_0402R_C_H016)'                   | 'RES,1.54K,1%,0.0625W,0402'                                                             | ''        
 'G155-01331-01' | '1.33KOHM'   | '1%'         = 'SMC_0402R'          | '(SMC_0402R_C)'                        | 'RES,1.33K,1%,0.063W,0402'                                                              | ''        
 'G155-01471-01' | '1.47KOHM'   | '1%'         = 'SMC_0402R_H016'     | '(SMC_0402R_C_H016)'                   | 'RES,1.47K,1%,0.063W,0402'                                                              | ''        
 'G152-10170-01' | '511OHM'     | '0.1%'       = 'SMC_0402R_H016'     | '(SMC_0402R_C_H016)'                   | 'RES,511OHM,0.1%,0.063W,0402'                                                           | ''        
 'G155-01101-01' | '1.1KOHM'    | '1%'         = 'SMC_0402R_H016'     | '(SMC_0402R_C_H016)'                   | 'RES,1.1K,1%,0.063W,0402'                                                               | ''        
 'G155-04221-01' | '4.22KOHM'   | '1%'         = 'SMC_0402R'          | '(SMC_0402R_C)'                        | 'RES,4.22K,1%,0.063W,0402'                                                              | ''        
 'G155-06193-01' | '619KOHM'    | '1%'         = 'SMC_0402R_H016'     | '(SMC_0402R_C_H016)'                   | 'RES,619K,1%,0.063W,0402'                                                               | ''        
 'G155-06042-01' | '60.4KOHM'   | '1%'         = 'SMC_0402R'          | '(SMC_0402R_C)'                        | 'RES,60.4K,1%,0.063W,0402'                                                              | ''        
 'G156-06190-01' | '619OHM'     | '1%'         = 'SMC_0603R'          | '(SMC_0603R)'                          | 'RES,619,1%,0.1W,0603'                                                                  | ''        
 'G152-10243-01' | '4.22KOHM'   | '0.1%'       = 'SMC_0402R_H014'     | '(SMC_0402R_C_H014)'                   | 'RES,4.22K,0.1%,0.063W,0402'                                                            | ''        
 'G155-08451-01' | '8.45KOHM'   | '1%'         = 'SMC_0402R_H016'     | '(SMC_0402R_C_H016)'                   | 'RES,8.45K,1%,0.063W,0402'                                                              | ''        
 'G155-02201-01' | '2.2KOHM'    | '1%'         = 'SMC_0402R_H016'     | '(SMC_0402R_C_H016)'                   | 'RES,2.2K,1%0.063W,0402'                                                                | 'NFND'    
 'G152-10176-01' | '1.1KOHM'    | '0.1%'       = 'SMC_0402R_H014'     | '(SMC_0402R_C_H014)'                   | 'RES,1.1K,0.1%,0.063W,0402'                                                             | ''        
 'G155-04530-01' | '453OHM'     | '1%'         = 'SMC_0402R_H016'     | '(SMC_0402R_C_H016)'                   | 'RES,453OHM,1%,0.063W,0402'                                                             | ''        
 'G155-01690-01' | '169OHM'     | '1%'         = 'SMC_0402R_H016'     | '(SMC_0402R_C_H016)'                   | 'RES,169,1%,0.063W,0402'                                                                | ''        
 'G155-01271-01' | '1.27KOHM'   | '1%'         = 'SMC_0402R'          | '(SMC_0402R_C)'                        | 'RES,1.27K,1%,0.063W,0402'                                                              | ''        
 'G152-10217-01' | '560OHM'     | '0.1%'       = 'SMC_0402R_H016'     | '(SMC_0402R_C_H016)'                   | 'RES,560,0.1%,0.063W,0402'                                                              | ''        
 'G155-03650-01' | '365OHM'     | '1%'         = 'SMC_0402R_H016'     | '(SMC_0402R_C_H016)'                   | 'RES,365,1%,0.063W,0402'                                                                | ''        
 'G155-01651-01' | '1.65KOHM'   | '1%'         = 'SMC_0402R_H016'     | '(SMC_0402R_C_H016)'                   | 'RES,1.65K,1%,0.063W,0402'                                                              | ''        
 'G155-03920-01' | '392OHM'     | '1%'         = 'SMC_0402R_H016'     | '(SMC_0402R_C_H016)'                   | 'RES,392,1%,0.0625W,0402'                                                               | ''        
 'G155-00660-01' | '60OHM'      | '1%'         = 'SMC_0402R_H016'     | '(SMC_0402R_C_H016)'                   | 'RES,60,1%,0.0625W,0402'                                                                | ''        
 'G155-03303-01' | '330KOHM'    | '1%'         = 'SMC_0402R_H016'     | '(SMC_0402R_C_H016)'                   | 'RES,330K,1%,0.0625W,0402'                                                              | ''        
 'G152-10315-01' | '6.8KOHM'    | '1%'         = 'SMC_0402R_H016'     | '(SMC_0402R_C_H016)'                   | 'RES,6.8K,1%,0.0625W,0402'                                                              | ''        
 'G152-10273-01' | '0.001OHM'   | '1%'         = 'SMC_2512R_V2'       | '(SMC_2512R_V2)'                       | 'RES,0.001,1%,2W,2512'                                                                  | 'NFND'    
 'G155-02493-01' | '249KOHM'    | '1%'         = 'SMC_0402R_H016'     | '(SMC_0402R_C_H016)'                   | 'RES,249K,1%,0.063W,0402'                                                               | ''        
 'G155-01103-01' | '110KOHM'    | '1%'         = 'SMC_0402R_H016'     | '(SMC_0402R_C_H016)'                   | 'RES,110K,1%,0.063W,0402'                                                               | ''        
 'G152-10290-01' | '0OHM'       | '1%'         = 'SMC_0805R_H024'     | '(SMC_0805R_H024)'                     | 'RES,0OHM,1%,0.125W,0805'                                                               | ''        
 'G155-01431-01' | '1.43KOHM'   | '1%'         = 'SMC_0402R_H016'     | '(SMC_0402R_C_H016)'                   | 'RES,1.43K,1%,0.063W,0402'                                                              | ''        
 'G152-10165-01' | '4.99KOHM'   | '0.5%'       = 'SMC_0402R_H014'     | '(SMC_0402R_C_H014)'                   | 'RES,4.99K,0.5%,0.063W,0402'                                                            | ''        
 'G155-04423-01' | '442KOHM'    | '1%'         = 'SMC_0402R_H016'     | '(SMC_0402R_C_H016)'                   | 'RES,442K,1%,0.0625W,0402'                                                              | ''        
 'G155-01240-01' | '124OHM'     | '1%'         = 'SMC_0402R_H016'     | '(SMC_0402R_C_H016)'                   | 'RES,124,1%,0.063W,0402'                                                                | ''        
 'G155-04753-01' | '475KOHM'    | '1%'         = 'SMC_0402R_H016'     | '(SMC_0402R_C_H016)'                   | 'RES,475K,1%,0.063W,0402'                                                               | ''        
 'A152-04321-DL' | '4.32KOHM'   | '0.1%'       = 'SMC_0402R_H016'     | '(SMC_0402R_C_H016)'                   | 'RES,4.32K,0.1%,0.063W,0402'                                                            | ''        
 'A152-03321-DL' | '3.32KOHM'   | '0.1%'       = 'SMC_0402R_H016'     | '(SMC_0402R_C_H016)'                   | 'RES,3.32K,0.1%,0.063W,0402'                                                            | ''        
 'A155-03651-DL' | '3.65KOHM'   | '1%'         = 'SMC_0402R_H016'     | '(SMC_0402R_C_H016)'                   | 'RES,3.65K,1%,0.063W,0402'                                                              | ''        
 'A155-02871-DL' | '2.87KOHM'   | '1%'         = 'SMC_0402R_H016'     | '(SMC_0402R_C_H016)'                   | 'RES,2.87K,1%,0.063W,0402'                                                              | ''        
 'A152-03921-DL' | '3.92KOHM'   | '0.1%'       = 'SMC_0402R_H016'     | '(SMC_0402R_C_H016)'                   | 'RES,3.92K,0.1%,0.063W,0402'                                                            | ''        
 'A152-04991-DL' | '4.99KOHM'   | '0.5%'       = 'SMC_0402R_H016'     | '(SMC_0402R_C_H016)'                   | 'RES,4.99K,0.5%,0.063W,0402'                                                            | ''        
 'G155-07871-01' | '7.87KOHM'   | '1%'         = 'SMC_0402R_H016'     | '(SMC_0402R_C_H016)'                   | 'RES,7.87K,1%,0.063W,0402'                                                              | ''        
 'G155-01784-01' | '1.78MOHM'   | '1%'         = 'SMC_0402R_H016'     | '(SMC_0402R_C_H016)'                   | 'RES,1.78MOHM,1%,0.0625W,0402'                                                          | ''        
 'G157-002R0-01' | '2OHM'       | '1%'         = 'SMC_0805R_H024'     | '(SMC_0805R_H024)'                     | 'RES,2 OHM,1%,0.125W,0805'                                                              | ''        
 'G156-03R01-01' | '3.01OHM'    | '1%'         = 'SMC_0603R_H022'     | '(SMC_0603R_H022)'                     | 'RES,3.01 OHM,1%,0.1W,0603'                                                             | ''        
 'G155-01472-01' | '14.7KOHM'   | '1%'         = 'SMC_0402R_H016'     | '(SMC_0402R_C_H016)'                   | 'RES,14.7K,1%,0.063W,0402'                                                              | ''        
 'G152-10262-01' | '0.0015OHM'  | '1%'         = 'SMC_2512R_V2_H041'  | '(SMC_2512R_V2_H041)'                  | 'RES,0.0015 OHM,1%,2W,2512'                                                             | ''        
 'G152-10317-01' | '6.65KOHM'   | '0.1%'       = 'SMC_0402R_H016'     | '(SMC_0402R_C_H016)'                   | 'RES,6.65K,0.1%,1/16W,0402,25PPM'                                                       | ''        
 'G152-10316-01' | '4.99KOHM'   | '0.1%'       = 'SMC_0402R_H016'     | '(SMC_0402R_C_H016)'                   | 'RES,4.99K,0.1%,1/16W,0402,25PPM'                                                       | 'NFND'    
 'G156-04751-01' | '4.75KOHM'   | '1%'         = 'SMC_0603R_H022'     | '(SMC_0603R_H022)'                     | 'RES,4.75K,1%,0.1W,0603'                                                                | ''        
 'G152-10283-01' | '49.9OHM'    | '1%'         = 'SMC_2010R_H028'     | '(SMC_2010R_H028)'                     | 'RES,49.9OHM,1%,1W,2010'                                                                | ''        
 'G156-04750-01' | '475OHM'     | '1%'         = 'SMC_0603R'          | '(SMC_0603R)'                          | 'RES,475,1%,0.1W,0603'                                                                  | ''        
 'G156-04222-01' | '42.2KOHM'   | '1%'         = 'SMC_0603R_H022'     | '(SMC_0603R_H022)'                     | 'RES,42.2K,1%,0.0625W,0603'                                                             | ''        
 'G155-01183-01' | '118KOHM'    | '1%'         = 'SMC_0402R_H016'     | '(SMC_0402R_C_H016)'                   | 'RES,118K,1%,0.063W,0402'                                                               | ''        
 'G156-08252-01' | '82.5KOHM'   | '1%'         = 'SMC_0603R'          | '(SMC_0603R)'                          | 'RES,82.5K,1%,0.1W,0603'                                                                | ''        
 'G155-02802-01' | '28KOHM'     | '1%'         = 'SMC_0402R_H016'     | '(SMC_0402R_C_H016)'                   | 'RES,28K,1%,0.063W,0402'                                                                | ''        
 'G158-01004-01' | '1MOHM'      | '1%'         = 'SMC_1206R_H028'     | '(SMC_1206R_H028)'                     | 'RES,1MOHM,1%,0.25W,1206'                                                               | ''        
 'G156-04992-01' | '49.9KOHM'   | '1%'         = 'SMC_0603R'          | '(SMC_0603R)'                          | 'RES,49.9K,1%,0.1W,0603'                                                                | ''        
 'G155-097R6-01' | '97.6OHM'    | '1%'         = 'SMC_0402R_H016'     | '(SMC_0402R_C_H016)'                   | 'RES,97.6,1%,0.063W,0402'                                                               | ''        
 'G155-05491-01' | '5.49KOHM'   | '1%'         = 'SMC_0402R_H016'     | '(SMC_0402R_C_H016)'                   | 'RES,5.49K,1%,0.063W,0402'                                                              | ''        
 'G154-04701-01' | '4.7KOHM'    | '1%'         = 'SMC_0201R'          | '(SMC_0201R_C)'                        | 'RES,4.7K,1%,0.05W,0201'                                                                | ''        
 'G155-01131-01' | '1.13KOHM'   | '1%'         = 'SMC_0402R_H016'     | '(SMC_0402R_C_H016)'                   | 'RES,1.13K,1%,0.063W,0402'                                                              | ''        
 'G155-02151-01' | '2.15KOHM'   | '1%'         = 'SMC_0402R_H016'     | '(SMC_0402R_C_H016)'                   | 'RES,2.15K,1%,0.063W,0402'                                                              | ''        
 'G152-10320-01' | '562OHM'     | '1%'         = 'SMC_1206R_H026'     | '(SMC_1206R_H026)'                     | 'RES,562,1%,0.5W,1206'                                                                  | ''        
 'G152-10321-01' | '100OHM'     | '1%'         = 'SMC_2512R_H028'     | '(SMC_2512R_H028)'                     | 'RES,100OHM,1%,1W,2512'                                                                 | ''        
 'G152-10322-01' | '1KOHM'      | '1%'         = 'SMC_2512R_H028'     | '(SMC_2512R_H028)'                     | 'RES,1KOHM,1%,1W,2512'                                                                  | ''        
 'G152-10140-01' | '2.0KOHM'    | '0.1%'       = 'SMC_0402R_H014'     | '(SMC_0402R_C_H014)'                   | 'RES,2.0K,0.1%,0.063W,0402'                                                             | ''        
 'G155-04421-01' | '4.42KOHM'   | '1%'         = 'SMC_0402R_H016'     | '(SMC_0402R_C_H016)'                   | 'RES,4.42K,1%,0.063W,0402'                                                              | ''        
 'G155-09761-01' | '9.76KOHM'   | '1%'         = 'SMC_0402R_H016'     | '(SMC_0402R_C_H016)'                   | 'RES,9.76K,1%,0.063W,0402'                                                              | ''        
 'G155-02053-01' | '205KOHM'    | '1%'         = 'SMC_0402R_H016'     | '(SMC_0402R_C_H016)'                   | 'RES,205K,1%,0.063W,0402'                                                               | ''        
 'G152-10323-01' | '390OHM'     | '1%'         = 'SMC_2512R_V5_H032'  | '(SMC_2512R_V5_H032)'                  | 'RES, 390 OHM, 1%, 2W, 2512'                                                            | ''        
 'G152-10241-01' | '3.32KOHM'   | '0.1%'       = 'SMC_0402R_H014'     | '(SMC_0402R_C_H014)'                   | 'RES,3.32K,0.1%,0.063W,0402'                                                            | ''        
 'G152-10269-01' | '4.12KOHM'   | '0.1%'       = 'SMC_0402R_H016'     | '(SMC_0402R_C_H016)'                   | 'RES,4.12K,0.1%,0.063W,0402'                                                            | ''        
 'G155-01203-01' | '120KOHM'    | '1%'         = 'SMC_0402R_H016'     | '(SMC_0402R_C_H016)'                   | 'RES,120K,1%,0.063W,0402'                                                               | ''        
 'G152-10324-01' | '0.5OHM'     | '1%'         = 'SMC_2512R_H028'     | '(SMC_2512R_H028)'                     | 'RES,0.5,1%,1W,2512'                                                                    | ''        
 'A152-01691-DL' | '1.69KOHM'   | '0.5%'       = 'SMC_0402R_H016'     | '(SMC_0402R_C_H016)'                   | 'RES,1.69K,0.5%,0.063W,0402'                                                            | ''        
 'A152-03601-DL' | '3.6KOHM'    | '0.5%'       = 'SMC_0402R_H016'     | '(SMC_0402R_C_H016)'                   | 'RES,3.6K,0.5%,0.063W,0402'                                                             | ''        
 'A152-06812-DL' | '68.1KOHM'   | '0.5%'       = 'SMC_0402R_H016'     | '(SMC_0402R_C_H016)'                   | 'RES,68.1K,0.5%,0.063W,0402'                                                            | ''        
 'A152-04122-DL' | '41.2KOHM'   | '0.5%'       = 'SMC_0402R_H016'     | '(SMC_0402R_C_H016)'                   | 'RES,41.2K,0.5%,0.063W,0402'                                                            | ''        
 'A152-01871-DL' | '1.87KOHM'   | '0.5%'       = 'SMC_0603R_H024'     | '(SMC_0603R_H024)'                     | 'RES,1.87K,0.5%,0.1W,0603'                                                              | ''        
 'A152-05111-DL' | '5.11KOHM'   | '0.5%'       = 'SMC_0603R_H024'     | '(SMC_0603R_H024)'                     | 'RES,5.11K,0.5%,0.1W,0603'                                                              | ''        
 'G152-10182-01' | '8.25KOHM'   | '0.1%'       = 'SMC_0402R_H014'     | '(SMC_0402R_C_H014)'                   | 'RES,8.25K,0.1%,0.063W,0402'                                                            | ''        
 'G152-10088-01' | '0.0005OHM'  | '1%'         = 'SMC_2512R_H035'     | '(SMC_2512R_H035)'                     | 'RES,0.0005,1%,3W,2512'                                                                 | ''        
 'G155-069R8-01' | '69.8OHM'    | '1%'         = 'SMC_0402R_H016'     | '(SMC_0402R_C_H016)'                   | 'RES,69.8,1%,0.0625W,0402'                                                              | ''        
 'G156-06811-01' | '6.81KOHM'   | '1%'         = 'SMC_0603R_H022'     | '(SMC_0603R_H022)'                     | 'RES,6.81K,1%,0.1W,0603'                                                                | ''        
 'G158-03001-01' | '3KOHM'      | '1%'         = 'SMC_1206R_H028'     | '(SMC_1206R_H028)'                     | 'RES,3K,1%,0.25W,1206'                                                                  | ''        
 'G155-019R1-01' | '19.1OHM'    | '1%'         = 'SMC_0402R_H016'     | '(SMC_0402R_C_H016)'                   | 'RES,19.1,1%,0.063W,0402'                                                               | ''        
 'G152-10325-01' | '0.0005OHM'  | '1%'         = 'SMC_2512R_V3_H057'  | '(SMC_2512R_V3_H057)'                  | 'RES,0.0005OHM,1%,2W,2512'                                                              | ''        
 'G152-10326-01' | '0.068OHM'   | '1%'         = 'SMC_1206R_H028'     | '(SMC_1206R_H028)'                     | 'RES, 0.068OHM, 1%, .5W, 1206'                                                          | ''        
 'G152-10286-01' | '120OHM'     | '1%'         = 'SMC_2512R_H026'     | '(SMC_2512R_H026)'                     | 'RES,120OHM,1%,2W,2512'                                                                 | ''        
 'G156-01101-01' | '1.10KOHM'   | '1%'         = 'SMC_0603R_H022'     | '(SMC_0603R_H022)'                     | 'RES,1.10K,1%,0.1W,0603'                                                                | ''        
 'G155-02942-01' | '29.4KOHM'   | '1%'         = 'SMC_0402R_H016'     | '(SMC_0402R_C_H016)'                   | 'RES,29.4K,1%,0.063W,0402'                                                              | ''        
 'G152-10256-01' | '48.7KOHM'   | '0.1%'       = 'SMC_0402R_H014'     | '(SMC_0402R_C_H014)'                   | 'RES,48.7K,0.1%,0.063W,0402'                                                            | ''        
 'G156-01181-01' | '1.18KOHM'   | '1%'         = 'SMC_0603R'          | '(SMC_0603R)'                          | 'RES,1.18K,1%,0.1W,0603'                                                                | ''        
 'G152-10229-01' | '34.8KOHM'   | '0.1%'       = 'SMC_0402R_H014'     | '(SMC_0402R_C_H014)'                   | 'RES,34.8K,0.1%,0.063W,0402'                                                            | ''        
 'G155-06982-01' | '69.8KOHM'   | '1%'         = 'SMC_0402R'          | '(SMC_0402R_C)'                        | 'RES,69.8K,1%,0.063W,0402'                                                              | ''        
 'G155-04322-01' | '43.2KOHM'   | '1%'         = 'SMC_0402R_H016'     | '(SMC_0402R_C_H016)'                   | 'RES,43.2K,1%,0.063W,0402'                                                              | ''        
 'G155-07152-01' | '71.5KOHM'   | '1%'         = 'SMC_0402R_H016'     | '(SMC_0402R_C_H016)'                   | 'RES,71.5K,1%,0.063W,0402'                                                              | ''        
 'G155-01780-01' | '178OHM'     | '1%'         = 'SMC_0402R_H016'     | '(SMC_0402R_C_H016)'                   | 'RES,178,1%,0.063W,0402'                                                                | ''        
 'G155-01051-01' | '1.05KOHM'   | '1%'         = 'SMC_0402R_H016'     | '(SMC_0402R_C_H016)'                   | 'RES,1.05K,1%,0.063W,0402'                                                              | ''        
 'G155-014R7-01' | '14.7OHM'    | '1%'         = 'SMC_0402R_H016'     | '(SMC_0402R_C_H016)'                   | 'RES,14.7OHM,1%,0.063W,0402'                                                            | ''        
 'G155-01242-01' | '12.4KOHM'   | '1%'         = 'SMC_0402R_H016'     | '(SMC_0402R_C_H016)'                   | 'RES,12.4K,1%,0.063W,0402'                                                              | ''        
 'G152-10230-01' | '301KOHM'    | '0.1%'       = 'SMC_0603R_H018'     | '(SMC_0603R_H018)'                     | 'RES,301K,0.1%,0.1W,0603'                                                               | ''        
 'G152-10327-01' | '3.92KOHM'   | '0.1%'       = 'SMC_0402R_H016'     | '(SMC_0402R_C_H016)'                   | 'RES,3.92K,0.1%,1/16W,0402,25PPM'                                                       | ''        
 'G155-03093-01' | '309KOHM'    | '1%'         = 'SMC_0402R_H016'     | '(SMC_0402R_C_H016)'                   | 'RES,309K,1%,0.063W,0402'                                                               | ''        
 'G157-020R0-01' | '20OHM'      | '1%'         = 'SMC_0805R_H024'     | '(SMC_0805R_H024)'                     | 'RES,20OHM,1%,0.25W,0805'                                                               | ''        
 'G157-010R0-01' | '10OHM'      | '1%'         = 'SMC_0805R_H026'     | '(SMC_0805R_H026)'                     | 'RES,10OHM,1%,0.25W,0805'                                                               | ''        
 'G157-02493-01' | '249KOHM'    | '1%'         = 'SMC_0805R_H026'     | '(SMC_0805R_H026)'                     | 'RES,249K,1%,0.125W,0805'                                                               | ''        
 'G157-03302-01' | '33KOHM'     | '1%'         = 'SMC_0805R_H026'     | '(SMC_0805R_H026)'                     | 'RES,33K,1%,0.125W,0805'                                                                | ''        
 'G157-03301-01' | '3.3KOHM'    | '1%'         = 'SMC_0805R_H026'     | '(SMC_0805R_H026)'                     | 'RES,3.3K,1%,0.125W,0805'                                                               | ''        
 'G157-05903-01' | '590KOHM'    | '1%'         = 'SMC_0805R_H026'     | '(SMC_0805R_H026)'                     | 'RES,590K,1%,0.125W,0805'                                                               | ''        
 'G157-04301-01' | '4.3KOHM'    | '1%'         = 'SMC_0805R_H028'     | '(SMC_0805R_H028)'                     | 'RES,4.3K,1%,0.125W,0805'                                                               | ''        
 'G157-01433-01' | '143KOHM'    | '1%'         = 'SMC_0805R_H026'     | '(SMC_0805R_H026)'                     | 'RES,143K,1%,0.125W,0805'                                                               | ''        
 'G157-02494-01' | '2.49MOHM'   | '1%'         = 'SMC_0805R_H026'     | '(SMC_0805R_H026)'                     | 'RES,2.49M,1%,0.125W,0805'                                                              | ''        
 'G157-01504-01' | '1.5MOHM'    | '1%'         = 'SMC_0805R_H026'     | '(SMC_0805R_H026)'                     | 'RES,1.5M,1%,0.125W,0805'                                                               | ''        
 'G158-00R68-01' | '0.68OHM'    | '1%'         = 'SMC_1206R_H028'     | '(SMC_1206R_H028)'                     | 'RES,0.68,1%,0.25W,1206'                                                                | ''        
 'G158-00R51-01' | '0.51OHM'    | '1%'         = 'SMC_1206R_H028'     | '(SMC_1206R_H028)'                     | 'RES,0.51,1%,0.25W,1206'                                                                | ''        
 'G152-10328-01' | '2.49MOHM'   | '1%'         = 'SMC_2010R_H028'     | '(SMC_2010R_H028)'                     | 'RES,2.49M,1%,0.75W,2010'                                                               | ''        
 'G152-10329-01' | '10OHM'      | '5%'         = 'SMC_2512R_H028'     | '(SMC_2512R_H028)'                     | 'RES,10OHM,5%,1.5W,2512'                                                                | ''        
 'G152-10330-01' | '49.9KOHM'   | '1%'         = 'SMC_1210R_H028'     | '(SMC_1210R_H028)'                     | 'RES,49.9K,1%,0.5W,1210'                                                                | ''        
 'G157-02492-01' | '24.9KOHM'   | '1%'         = 'SMC_0805R_H026'     | '(SMC_0805R_H026)'                     | 'RES,24.9K,1%,0.125W,0805'                                                              | ''        
 'G156-03652-01' | '36.5KOHM'   | '1%'         = 'SMC_0603R'          | '(SMC_0603R)'                          | 'RES,36.5K,1%,0.1W,0603'                                                                | ''        
 'G152-10335-01' | '3.6KOHM'    | '0.1%'       = 'SMC_0402R_H016'     | '(SMC_0402R_C_H016)'                   | 'RES,3.6K,0.1%,0.063W,0402'                                                             | ''        
 'G152-10334-01' | '2.37KOHM'   | '0.1%'       = 'SMC_0402R_H016'     | '(SMC_0402R_C_H016)'                   | 'RES,2.37K,0.1%,0.063W,0402'                                                            | ''        
 'G152-10333-01' | '3.3OHM'     | '10%'        = 'R2_R276_P197'       | '(R2_R276_P197)'                       | 'RES,3.3OHM,10%,PULSE WITHSTAND,2W,DIP'                                                 | ''        
 'G156-03920-01' | '392OHM'     | '1%'         = 'SMC_0603R'          | '(SMC_0603R)'                          | 'RES,392,1%,0.1W,0603'                                                                  | ''        
 'G156-06810-01' | '681KOHM'    | '1%'         = 'SMC_0603R_H022'     | '(SMC_0603R_H022)'                     | 'RES,681,1%,0.1W,0603'                                                                  | ''        
 'G155-01072-01' | '10.7KOHM'   | '1%'         = 'SMC_0402R_H016'     | '(SMC_0402R_C_H016)'                   | 'RES,10.7K,1%,0.063W,0402'                                                              | ''        
 'G156-07681-01' | '7.68KOHM'   | '1%'         = 'SMC_0603R_H022'     | '(SMC_0603R_H022)'                     | 'RES,7.68K,1%,0.1W,0603'                                                                | ''        
 'A155-04532-DL' | '45.3KOHM'   | '1%'         = 'SMC_0402R_H016'     | '(SMC_0402R_C_H016)'                   | 'RES,45.3K,1%,0.063W,0402'                                                              | ''        
 'A155-01022-DL' | '10.2KOHM'   | '1%'         = 'SMC_0402R_H016'     | '(SMC_0402R_C_H016)'                   | 'RES,10.2K,1%,0.063W,0402'                                                              | ''        
 'A156-07502-DL' | '75KOHM'     | '1%'         = 'SMC_0603R_H022'     | '(SMC_0603R_H022)'                     | 'RES,75K,1%,0.1W,0603'                                                                  | ''        
 'G155-05111-01' | '5.11KOHM'   | '1%'         = 'SMC_0402R_H016'     | '(SMC_0402R_C_H016)'                   | 'RES,5.11K,1%,0.063W,0402'                                                              | ''        
 'G155-09310-01' | '931OHM'     | '1%'         = 'SMC_0402R_H016'     | '(SMC_0402R_C_H016)'                   | 'RES,931,1%,0.063W,0402'                                                                | 'NFND'    
 'G155-01021-01' | '1.02KOHM'   | '1%'         = 'SMC_0402R_H016'     | '(SMC_0402R_C_H016)'                   | 'RES,1.02K,1%,0.0625W,0402'                                                             | ''        
 'G156-09762-01' | '97.6KOHM'   | '1%'         = 'SMC_0603R_H022'     | '(SMC_0603R_H022)'                     | 'RES,97.6K,1%,0.1W,0603'                                                                | ''        
 'G155-02402-01' | '24KOHM'     | '1%'         = 'SMC_0402R_H016'     | '(SMC_0402R_C_H016)'                   | 'RES,24K,1%,0.0625W,0402'                                                               | ''        
 'G158-00R47-01' | '0.47OHM'    | '1%'         = 'SMC_1206R_H028'     | '(SMC_1206R_H028)'                     | 'RES,0.47,1%,0.25W,1206'                                                                | ''        
 'G152-10336-01' | '1.2KOHM'    | '0.1%'       = 'SMC_0402R_H016'     | '(SMC_0402R_C_H016)'                   | 'RES,1.2K,0.1%,0.063W,0402'                                                             | ''        
 'G152-10337-01' | '49.9OHM'    | '1%'         = 'SMC_2512R_H028'     | '(SMC_2512R_H028)'                     | 'RES,49.9,1%,1.5W,PULSE WITHSTAND,2512'                                                 | ''        
 'G154-01003-01' | '100KOHM'    | '1%'         = 'SMC_0201R'          | '(SMC_0201R_C)'                        | 'RES,100KOHM,1%,0.05W,0201'                                                             | ''        
 'G152-10210-01' | '4.99KOHM'   | '0.1%'       = 'SMC_0402R_H014'     | '(SMC_0402R_C_H014)'                   | 'RES,4.99K,0.1%,0.063W,0402'                                                            | ''        
 'G152-10209-01' | '2.49KOHM'   | '0.1%'       = 'SMC_0402R_H014'     | '(SMC_0402R_C_H014)'                   | 'RES,2.49K,0.1%,0.063W,0402'                                                            | ''        
 'G152-10244-01' | '8.87KOHM'   | '0.1%'       = 'SMC_0402R_H014'     | '(SMC_0402R_C_H014)'                   | 'RES,8.87K,0.1%,0.063W,0402'                                                            | ''        
 'G152-10240-01' | '1.5KOHM'    | '0.1%'       = 'SMC_0402R_H014'     | '(SMC_0402R_C_H014)'                   | 'RES,1.5K,0.1%,0.063W,0402'                                                             | ''        
 'G155-03743-01' | '374KOHM'    | '1%'         = 'SMC_0402R_H016'     | '(SMC_0402R_C_H016)'                   | 'RES,374K,1%,0.063W,0402'                                                               | ''        
 'G155-02321-01' | '2.32KOHM'   | '1%'         = 'SMC_0402R_H016'     | '(SMC_0402R_C_H016)'                   | 'RES,2.32K,1%,0.063W,0402'                                                              | ''        
 'G155-02551-01' | '2.55KOHM'   | '1%'         = 'SMC_0402R_H016'     | '(SMC_0402R_C_H016)'                   | 'RES,2.55K,1%,0.063W,0402'                                                              | ''        
 'G155-05601-01' | '5.6KOHM'    | '1%'         = 'SMC_0402R_H016'     | '(SMC_0402R_C_H016)'                   | 'RES,5.6K,1%,0.063W,0402'                                                               | ''        
 'G155-04870-01' | '487OHM'     | '1%'         = 'SMC_0402R_H016'     | '(SMC_0402R_C_H016)'                   | 'RES,487,1%,0.063W,0402'                                                                | ''        
 'G155-01053-01' | '105KOHM'    | '1%'         = 'SMC_0402R_H016'     | '(SMC_0402R_C_H016)'                   | 'RES,105K,1%,0.063W,0402'                                                               | ''        
 'G152-10135-01' | '26.1KOHM'   | '0.1%'       = 'SMC_0402R_H014'     | '(SMC_0402R_C_H014)'                   | 'RES,26.1K,0.1%,0.063W,0402'                                                            | ''        
 'G152-10129-01' | '51.1KOHM'   | '0.1%'       = 'SMC_0402R_H014'     | '(SMC_0402R_C_H014)'                   | 'RES,51.1K,0.1%,0.063W,0402'                                                            | ''        
 'G152-10142-01' | '2.87KOHM'   | '0.1%'       = 'SMC_0402R_H014'     | '(SMC_0402R_C_H014)'                   | 'RES,2.87K,0.1%,0.063W,0402'                                                            | ''        
 'G155-01333-01' | '133KOHM'    | '1%'         = 'SMC_0402R_H016'     | '(SMC_0402R_C_H016)'                   | 'RES,133K,1%,0.063W,0402'                                                               | ''        
 'G155-04642-01' | '46.4KOHM'   | '1%'         = 'SMC_0402R_H016'     | '(SMC_0402R_C_H016)'                   | 'RES,46.4K,1%,0.063W,0402'                                                              | ''        
 'G154-000R0-05' | '0OHM'       | '5%'         = 'SMC_0201R'          | '(SMC_0201R_C,C0201-GLASS-S0)'                        | 'RES,0,5%,0.05W,0201,JUMPER'                                                            | ''        
 'G155-02403-01' | '240KOHM'    | '1%'         = 'SMC_0402R_H016'     | '(SMC_0402R_C_H016)'                   | 'RES,240K,1%,0.0625W,0402'                                                              | ''        
 'G157-01R91-01' | '1.91OHM'    | '1%'         = 'SMC_0805R_H026'     | '(SMC_0805R_H026)'                     | 'RES, 1.91OHM, 1%, 0.125W, 0805'                                                        | ''        
 'G157-02002-01' | '20.0KOHM'   | '1%'         = 'SMC_0805R_H024'     | '(SMC_0805R_H024)'                     | 'RES, 20.0K, 1%, 0.125W, 0805'                                                          | ''        
 'G157-00512-05' | '5.1KOHM'    | '5%'         = 'SMC_0805R_H024'     | '(SMC_0805R_H024)'                     | 'RES, 5.1K, 5%, 0.125W, 0805'                                                           | ''        
 'G156-01302-01' | '13.0KOHM'   | '1%'         = 'SMC_0603R_H022'     | '(SMC_0603R_H022)'                     | 'RES,13.0K,1%,0.1W,0603'                                                                | ''        
 'G155-004R7-05' | '4.7OHM'     | '5%'         = 'SMC_0402R_H016'     | '(SMC_0402R_C_H016)'                   | 'RES, 4.7 OHM, 5%, 0.063W, 0402'                                                        | ''        
 'G155-02610-01' | '261OHM'     | '1%'         = 'SMC_0402R_H016'     | '(SMC_0402R_C_H016)'                   | 'RES,261,1%,0.063W,0402'                                                                | ''        
 'G152-10220-01' | '5.6KOHM'    | '0.1%'       = 'SMC_0402R_H016'     | '(SMC_0402R_C_H016)'                   | 'RES,5.6K,0.1%,0.063W,0402'                                                             | ''        
 'G155-00002-01' | '1.87KOHM'   | '0.1%'       = 'SMC_0402R_H016'     | '(SMC_0402R_C_H016)'                   | 'RES,1.87K,0.1%,0.063W,0402'                                                            | ''        
 'G152-10341-01' | '15KOHM'     | '0.1%'       = 'SMC_0402R_H016'     | '(SMC_0402R_C_H016)'                   | 'RES, 15K, 0.1%, 0.063W, 0402'                                                          | ''        
 'G152-10183-01' | '24.9KOHM'   | '0.1%'       = 'SMC_0402R_H014'     | '(SMC_0402R_C_H014)'                   | 'RES,24.9K,0.1%,0.063W,0402'                                                            | ''        
 'G157-04R70-01' | '4.7OHM'     | '1%'         = 'SMC_0805R_H028'     | '(SMC_0805R_H028)'                     | 'RES,4.7,1%,0.125W,0805'                                                                | ''        
 'G152-10207-01' | '3.83KOHM'   | '0.1%'       = 'SMC_0402R_H014'     | '(SMC_0402R_C_H014)'                   | 'RES,3.83K,0.1%,0.063W,0402'                                                            | ''        
 'G152-10181-01' | '1.27KOHM'   | '0.1%'       = 'SMC_0402R_H014'     | '(SMC_0402R_C_H014)'                   | 'RES,1.27K,0.1%,0.063W,0402'                                                            | ''        
 'G156-02R20-01' | '2.2OHM'     | '1%'         = 'SMC_0603R_H024'     | '(SMC_0603R_H024)'                     | 'RES,2.2,1%,0.1W,0603'                                                                  | 'NFND'    
 'G152-10343-01' | '52.3KOHM'   | '0.1%'       = 'SMC_0402R_H016'     | '(SMC_0402R_C_H016)'                   | 'RES,52.3K,0.1%,0.063W,0402'                                                            | ''        
 'G152-10346-01' | '590OHM'     | '0.1%'       = 'SMC_0402R_H016'     | '(SMC_0402R_C_H016)'                   | 'RES,590OHM,0.1%,0.063W,0402'                                                           | ''        
 'G152-10347-01' | '3.16KOHM'   | '0.1%'       = 'SMC_0402R_H016'     | '(SMC_0402R_C_H016)'                   | 'RES,3.16KOHM,0.1%,0.063W,0402'                                                         | ''        
 'G152-10342-01' | '2.26KOHM'   | '0.1%'       = 'SMC_0402R_H016'     | '(SMC_0402R_C_H016)'                   | 'RES,2.26KOHM,0.1%,0.063W,0402'                                                         | ''        
 'G152-10345-01' | '1.65KOHM'   | '0.1%'       = 'SMC_0402R_H016'     | '(SMC_0402R_C_H016)'                   | 'RES,1.65KOHM,0.1%,0.063W,0402'                                                         | ''        
 'G152-10344-01' | '30KOHM'     | '0.1%'       = 'SMC_0402R_H016'     | '(SMC_0402R_C_H016)'                   | 'RES,30KOHM,0.1%,0.063W,0402'                                                           | ''        
 'G155-03741-01' | '3.74KOHM'   | '1%'         = 'SMC_0402R_H016'     | '(SMC_0402R_C_H016)'                   | 'RES,3.74K,1%,0.063W,0402'                                                              | ''        
 'G155-01963-01' | '196KOHM'    | '1%'         = 'SMC_0402R_H016'     | '(SMC_0402R_C_H016)'                   | 'RES,196K,1%,0.063W,0402'                                                               | ''        
 'G152-10197-01' | '0.0016OHM'  | '1%'         = 'SMC_2512R_V2'       | '(SMC_2512R_V2)'                       | 'RES,0.0016OHM,1%,3W,2512'                                                              | ''        
 'G152-10239-01' | '2.4KOHM'    | '0.1%'       = 'SMC_0402R_H014'     | '(SMC_0402R_C_H014)'                   | 'RES,2.4K,0.1%,0.063W,0402'                                                             | ''        
 'G155-03241-01' | '3.24KOHM'   | '1%'         = 'SMC_0402R_H014'     | '(SMC_0402R_C_H014)'                   | 'RES,3.24K,1%,0.063W,0402'                                                              | ''        
 'G155-01542-01' | '15.4KOHM'   | '1%'         = 'SMC_0402R_H016'     | '(SMC_0402R_C_H016)'                   | 'RES,15.4K,1%,0.063W,0402'                                                              | ''        
 'G155-01272-01' | '12.7KOHM'   | '1%'         = 'SMC_0402R'          | '(SMC_0402R_C)'                        | 'RES,12.7K,1%,0.063W,0402'                                                              | ''        
 'G155-06043-01' | '604KOHM'    | '1%'         = 'SMC_0402R_H016'     | '(SMC_0402R_C_H016)'                   | 'RES,604K,1%,0.0625W,0402'                                                              | ''        
 'G156-01622-01' | '16.2KOHM'   | '1%'         = 'SMC_0603R_H022'     | '(SMC_0603R_H022)'                     | 'RES,16.2K,1%,0.1W,0603'                                                                | ''        
 'G155-01962-01' | '19.6KOHM'   | '1%'         = 'SMC_0402R'          | '(SMC_0402R_C)'                        | 'RES,19.6K,1%,0.0625W,0402'                                                             | ''        
 'G155-02673-01' | '267KOHM'    | '1%'         = 'SMC_0402R_H016'     | '(SMC_0402R_C_H016)'                   | 'RES,267K,1%,0.063W,0402'                                                               | ''        
 'G155-01433-01' | '143KOHM'    | '1%'         = 'SMC_0402R_H016'     | '(SMC_0402R_C_H016)'                   | 'RES,143K,1%,0.0625W,0402'                                                              | ''        
 'G152-10348-01' | '140KOHM'    | '0.1%'       = 'SMC_0402R_H016'     | '(SMC_0402R_C_H016)'                   | 'RES,140KOHM,0.1%,0.0625W,0402'                                                         | ''        
 '220-055360'    | '4.02KOHM'   | '1%'         = 'SMC_0402R_H016'     | '(SMC_0402R_C_H016)'                   | 'RES,4.02K,1%,0.063W,0402'                                                              | 'NFND'    
 'G156-02493-01' | '249KOHM'    | '1%'         = 'SMC_0603R_H024'     | '(SMC_0603R_H024)'                     | 'RES,249K,1%,0.1W,0603'                                                                 | ''        
 'G156-07322-01' | '73.2KOHM'   | '1%'         = 'SMC_0603R_H024'     | '(SMC_0603R_H024)'                     | 'RES,73.2K,1%,0.1W,0603'                                                                | ''        
 'G156-00910-01' | '91OHM'      | '1%'         = 'SMC_0603R_H024'     | '(SMC_0603R_H024)'                     | 'RES,91,1%,0.1W,0603'                                                                   | ''        
 'G156-05493-01' | '549KOHM'    | '1%'         = 'SMC_0603R_H024'     | '(SMC_0603R_H024)'                     | 'RES,549K,1%,0.1W,0603'                                                                 | ''        
 'G152-10349-01' | '0.015OHM'   | '1%'         = 'SMC_0805R_H024'     | '(SMC_0805R_H024)'                     | 'RES,0.015,1%,0.5W,0805'                                                                | ''        
 'G152-10350-01' | '44.2KOHM'   | '0.1%'       = 'SMC_0402R_H014'     | '(SMC_0402R_C_H014)'                   | 'RES,44.2K,0.1%,0.063W,0402'                                                            | ''        
 'G152-10351-01' | '2.8KOHM'    | '0.1%'       = 'SMC_0402R_H016'     | '(SMC_0402R_C_H016)'                   | 'RES,2.8K,0.1%,0.063W,0402'                                                             | ''        
 'G155-06813-01' | '681KOHM'    | '1%'         = 'SMC_0402R_H016'     | '(SMC_0402R_C_H016)'                   | 'RES,681K,1%,0.063W,0402'                                                               | ''        
 'G152-10352-01' | '176KOHM'    | '0.5%'       = 'SMC_0603R_H022'     | '(SMC_0603R_H022)'                     | 'RES,176K,0.5%,0.1W,0603'                                                               | ''        
 'G156-00163-01' | '16KOHM'     | '1%'         = 'SMC_0603R_H022'     | '(SMC_0603R_H022)'                     | 'RES,16K,1%,0.1W,0603'                                                                  | ''        
 'G156-00113-01' | '11KOHM'     | '1%'         = 'SMC_0603R_H022'     | '(SMC_0603R_H022)'                     | 'RES,11K,1%,0.1W,0603'                                                                  | ''        
 'G156-03160-01' | '316OHM'     | '1%'         = 'SMC_0603R_H024'     | '(SMC_0603R_H024)'                     | 'RES,316,1%,0.1W,0603'                                                                  | ''        
 'G155-09530-01' | '953OHM'     | '1%'         = 'SMC_0402R_H016'     | '(SMC_0402R_C_H016)'                   | 'RES,953,1%,0.063W,0402'                                                                | ''        
 'G152-10354-01' | '68KOHM'     | '0.1%'       = 'SMC_0402R_H016'     | '(SMC_0402R_C_H016)'                   | 'RES,68K,0.1%,0.063W,0402'                                                              | ''        
 'G152-10355-01' | '0.002OHM'   | '1%'         = 'SMC_2512R_V2'       | '(SMC_2512R_V2)'                       | 'RES,0.002,1%,3W,2512'                                                                  | ''        
 'G152-10353-01' | '0.005OHM'   | '1%'         = 'SMC_0612R'          | '(SMC_0612R)'                          | 'RES,0.005,1%,1.5W,0612'                                                                | ''        
 'G155-04223-01' | '422KOHM'    | '1%'         = 'SMC_0402R_H016'     | '(SMC_0402R_C_H016)'                   | 'RES,422K,1%,0.063W,0402'                                                               | 'OBSOLETE'
 'G155-01652-01' | '16.5KOHM'   | '1%'         = 'SMC_0402R_H016'     | '(SMC_0402R_C_H016)'                   | 'RES,16.5K,1%,0.063W,0402'                                                              | ''        
 'G155-01603-01' | '160KOHM'    | '1%'         = 'SMC_0402R_H016'     | '(SMC_0402R_C_H016)'                   | 'RES,160K,1%,0.063W,0402'                                                               | ''        
 'G152-10356-01' | '0.01OHM'    | '5%'         = 'SMC_2010R_V1'       | '(SMC_2010R_V1)'                       | 'RES, 0.01, 5%, 1W, 2010'                                                               | ''        
 'G155-005R1-05' | '5.1OHM'     | '5%'         = 'SMC_0402R_H016'     | '(SMC_0402R_C_H016)'                   | 'RES,5.1,5%,0.0625W,0402'                                                               | ''        
 'G152-10152-01' | '1.93KOHM'   | '0.1%'       = 'SMC_0603R_H022'     | '(SMC_0603R_H022)'                     | 'RES,1.93K,0.063W, 0.1%,0603'                                                           | ''        
 'G152-10245-01' | '3.3KOHM'    | '0.1%'       = 'SMC_0402R_H014'     | '(SMC_0402R_C_H014)'                   | 'RES,3.3K,0.1%,0.063W,0402'                                                             | ''        
 'G155-01870-01' | '187OHM'     | '1%'         = 'SMC_0402R_H016'     | '(SMC_0402R_C_H016)'                   | 'RES, 187OHM, 1%, 1/16W, 0402'                                                          | ''        
 'G152-10124-01' | '4.7KOHM'    | '0.1%'       = 'SMC_0402R_H014'     | '(SMC_0402R_C_H014)'                   | 'RES,4.7K,0.1%,0.063W,0402'                                                             | ''        
 'G152-10180-01' | '14.3KOHM'   | '0.1%'       = 'SMC_0402R_H014'     | '(SMC_0402R_C_H014)'                   | 'RES,14.3K,0.1%,0.063W,0402'                                                            | ''        
 'G152-10257-01' | '45.3KOHM'   | '0.1%'       = 'SMC_0402R_H014'     | '(SMC_0402R_C_H014)'                   | 'RES,45.3K,0.1%,0.063W,0402'                                                            | ''        
 'G155-051R0-01' | '51OHM'      | '1%'         = 'SMC_0402R_H016'     | '(SMC_0402R_C_H016)'                   | 'RES,51,1%,0.063W,0402'                                                                 | ''        
 'G152-10227-01' | '680OHM'     | '0.1%'       = 'SMC_0402R_H016'     | '(SMC_0402R_C_H016)'                   | 'RES,680,0.1%,0.063W,0402'                                                              | ''        
 'G152-10221-01' | '249OHM'     | '0.1%'       = 'SMC_0805R_H022'     | '(SMC_0805R_H022)'                     | 'RES,249,0.1%,0.125W,0805'                                                              | ''        
 'G152-10019-01' | '665OHM'     | '1%'         = 'SMC_0402R_H016'     | '(SMC_0402R_C_H016)'                   | 'RES,665OHM,1%,0.063W,0402'                                                             | ''        
 'G152-10226-01' | '562OHM'     | '0.1%'       = 'SMC_0402R_H016'     | '(SMC_0402R_C_H016)'                   | 'RES,562,0.1%,0.063W,0402'                                                              | ''        
 'G156-01473-01' | '147KOHM'    | '1%'         = 'SMC_0603R_H022'     | '(SMC_0603R_H022)'                     | 'RES,147K,1%,0.1W,0603'                                                                 | ''        
 'G156-00103-05' | '10KOHM'     | '5%'         = 'SMC_0603R_H022'     | '(SMC_0603R_H022)'                     | 'RES,10K,5%,0.1W,0603'                                                                  | 'NFND'    
 'G155-01872-01' | '18.7KOHM'   | '1%'         = 'SMC_0402R_H016'     | '(SMC_0402R_C_H016)'                   | 'RES,18.7K,1%,0.0625W,0402'                                                             | ''        
 'G152-10198-01' | '0.0022OHM'  | '1%'         = 'SMC_2512R_V2'       | '(SMC_2512R_V2)'                       | 'RES,0.0022OHM,1%,3W,2512'                                                              | ''        
 'G155-01133-01' | '113KOHM'    | '1%'         = 'SMC_0402R_H016'     | '(SMC_0402R_C_H016)'                   | 'RES,113K,1%,0.063W,0402'                                                               | ''        
 'G152-10360-01' | '1.2KOHM'    | '5%'         = 'SMC_2512R_H026'     | '(SMC_2512R_H026)'                     | 'RES, 1.2K, 5%, 1W, 2512'                                                               | ''        
 'G152-10117-01' | '100OHM'     | '1%'         = 'SMC_2512R_H026'     | '(SMC_2512R_H026)'                     | 'RES,100,1%,2W,2512'                                                                    | 'NFND'    
 'G152-10361-01' | '6.49KOHM'   | '0.1%'       = 'SMC_0402R_H016'     | '(SMC_0402R_C_H016)'                   | 'RES,6.49K,0.1%,63MW,0402'                                                              | ''        
 'G152-10175-01' | '549OHM'     | '0.1%'       = 'SMC_0402R_H014'     | '(SMC_0402R_C_H014)'                   | 'RES,549,0.1%,0.063W,0402'                                                              | ''        
 'G152-10362-01' | '100OHM'     | '1%'         = 'SMC_2512R_H032'     | '(SMC_2512R_H032)'                     | 'RES,100,1%,2W,2512'                                                                    | ''        
 'G155-02803-01' | '280KOHM'    | '1%'         = 'SMC_0402R_H016'     | '(SMC_0402R_C_H016)'                   | 'RES,280K,1%,0.0625W,0402'                                                              | ''        
 'G152-10120-01' | '0OHM'       | 'JUMPER'     = 'SMC_1206R_H030'     | '(SMC_1206R_H030)'                     | 'RES,0,ZERO OHM JUMPER, 1206'                                                           | ''        
 'G152-10368-01' | '665OHM'     | '1%'         = 'SMC_0805R_H028'     | '(SMC_0805R_H028)'                     | 'RES, 665, 1%, 0.5W, 0805'                                                              | ''        
 'A157-000R0-DL' | '0OHM'       | '5%'         = 'SMC_0805R_H024'     | '(SMC_0805R_H024)'                     | 'RES,0,5%,0.125W,0805'                                                                  | ''        
 'A152-10123-DL' | '10KOHM'     | '0.1%'       = 'SMC_0402R_H016'     | '(SMC_0402R_H016)'                     | 'RES,10K,0.1%,0.063W,0402'                                                              | ''        
 'A152-10140-DL' | '2.0KOHM'    | '0.1%'       = 'SMC_0402R_H016'     | '(SMC_0402R_H016)'                     | 'RES,2.0K,0.1%,0.063W,0402'                                                             | ''        
 'G152-10370-01' | '13KOHM'     | '0.1%'       = 'SMC_0402R_H016'     | '(SMC_0402R_H016)'                     | 'RES,13K,0.1%,0.063W,0402'                                                              | ''        
 'G155-03002-01' | '30KOHM'     | '1%'         = 'SMC_0402R_H016'     | '(SMC_0402R_C_H016)'                   | 'RES,30K,1%,0.0625W,0402'                                                               | ''        
 'G152-10371-01' | '30OHM'      | '0.1%'       = 'SMC_0402R_H016'     | '(SMC_0402R_C_H016)'                   | 'RES,30,0.1%,0.0625W,0402'                                                              | ''        
 'G157-00750-01' | '75OHM'      | '1%'         = 'SMC_0805R_H026'     | '(SMC_0805R_H026)'                     | 'RES,75,1%,0.125W,0805'                                                                 | ''        
 'G152-10372-01' | '13KOHM'     | '0.1%'       = 'SMC_0402R_H016'     | '(SMC_0402R_C_H016)'                   | 'RES,13K,0.1%,0.063W,0402'                                                              | ''        
 'G154-02101-01' | '2.1KOHM'    | '1%'         = 'SMC_0201R_H010'     | '(SMC_0201R_C_H010)'                   | 'RES,2.1K,1%,1/20W,0201,-55C TO +125C'                                                  | ''        
 'G154-01431-01' | '1.43KOHM'   | '1%'         = 'SMC_0201R_H010'     | '(SMC_0201R_C_H010)'                   | 'RES,1.43K,1%,1/20W,0201,-55C TO +125C'                                                 | ''        
 'G154-08061-01' | '8.06KOHM'   | '1%'         = 'SMC_0201R_H010'     | '(SMC_0201R_C_H010)'                   | 'RES,8.06K,1%,1/20W,0201,-55C TO +125C'                                                 | ''        
 'G155-02203-01' | '220KOHM'    | '1%'         = 'SMC_0402R_H016'     | '(SMC_0402R_V2_H016,SMC_0402R_C_H016)' | 'RES,220K,1%,0.0625,0402'                                                               | ''        
 'G155-03903-01' | '390KOHM'    | '1%'         = 'SMC_0402R_H016'     | '(SMC_0402R_H016)'                     | 'RES,390K,1%,0.0625W,0402'                                                              | ''        
 'G155-02702-01' | '27KOHM'     | '1%'         = 'SMC_0402R_H016'     | '(SMC_0402R_C_H016)'                   | 'RES,27K,1%,0.0625W,0402'                                                               | ''        
 'G155-08863-01' | '886KOHM'    | '1%'         = 'SMC_0402R_H016'     | '(SMC_0402R_V2_H016,SMC_0402R_C_H016)' | 'RES,886K,1%,0.063W,0402'                                                               | ''        
 'G155-059R0-01' | '59OHM'      | '1%'         = 'SMC_0402R_H016'     | '(SMC_0402R_C_H016)'                   | 'RES,59,1%,0.063W,0402'                                                                 | ''        
 'G155-03004-01' | '3MOHM'      | '1%'         = 'SMC_0402R_H016'     | '(SMC_0402R_H016)'                     | 'RES,3M,1%,0.063W,0402'                                                                 | ''        
 'G155-01371-01' | '1.37KOHM'   | '1%'         = 'SMC_0402R_H016'     | '(SMC_0402R_C_H016)'                   | 'RES,1.37K,1%,0.063W,0402'                                                              | ''        
 'G152-10373-01' | '23.2KOHM'   | '0.1%'       = 'SMC_0402R_H016'     | '(SMC_0402R_C_H016)'                   | 'RES,23.2K,0.1%,0.063W,0402'                                                            | ''        
 'G155-07323-01' | '732KOHM'    | '1%'         = 'SMC_0402R_H016'     | '(SMC_0402R_C_H016)'                   | 'RES,732K,1%,0.063W,0402'                                                               | ''        
 'G155-03092-01' | '30.9KOHM'   | '1%'         = 'SMC_0402R_H016'     | '(SMC_0402R_H016)'                     | 'RES,30.9K,1%,0.063W,0402'                                                              | ''        
 'G155-06340-01' | '634OHM'     | '1%'         = 'SMC_0402R_H016'     | '(SMC_0402R_C_H016)'                   | 'RES,634,1%,0.063W,0402'                                                                | ''        
 'G155-01583-01' | '158KOHM'    | '1%'         = 'SMC_0402R_H016'     | '(SMC_0402R_C_H016)'                   | 'RES,158K,1%,0.063W,0402'                                                               | ''        
 'G155-03243-01' | '324KOHM'    | '1%'         = 'SMC_0402R_H016'     | '(SMC_0402R_C_H016)'                   | 'RES,324K,1%,0.063W,0402'                                                               | ''        
 'G155-04422-01' | '44.2KOHM'   | '1%'         = 'SMC_0402R_H016'     | '(SMC_0402R_C_H016)'                   | 'RES,44.2K,1%,0.063W,0402'                                                              | ''        
 'G152-10377-01' | '22OHM'      | '5%'         = 'SMC_1210R_H028'     | '(SMC_1210R_H028)'                     | 'RES,22OHM,5%,0.25W,1210,FUSING RESISTOR'                                               | ''        
 'G152-10378-01' | '10OHM'      | '5%'         = 'SMC_1210R_H028'     | '(SMC_1210R_H028)'                     | 'RES,10OHM,5%,0.25W,1210,FUSING RESISTOR'                                               | ''        
 'G152-10379-01' | '10OHM'      | '5%'         = 'SMC_1210R_H028'     | '(SMC_1210R_H028)'                     | 'RES,10 OHM,5%,0.5W,1210'                                                               | ''        
 'G155-05230-01' | '523OHM'     | '1%'         = 'SMC_0402R_H016'     | '(SMC_0402R_C_H016)'                   | 'RES,523,1%,0.063W,0402'                                                                | ''        
 'G154-01500-01' | '150OHM'     | '1%'         = 'SMC_0201R_H010'     | '(SMC_0201R_C_H010)'                   | 'RES,150,1%,0.05W,0201,-55C TO +125C'                                                   | ''        
 'G154-01200-01' | '120OHM'     | '1%'         = 'SMC_0201R_H010'     | '(SMC_0201R_C_H010)'                   | 'RES,120,1%,0.05W,0201,-55C TO +125C'                                                   | ''        
 'G154-033R0-01' | '33OHM'      | '1%'         = 'SMC_0201R_H010'     | '(SMC_0201R_C_H010)'                   | 'RES,33,1%,0.05W,0201,-55C TO +125C'                                                    | ''        
 'G154-01001-01' | '1KOHM'      | '1%'         = 'SMC_0201R_H010'     | '(SMC_0201R_C_H010)'                   | 'RES,1K,1%,0.05W,0201,-55C TO +125C'                                                    | ''        
 'G154-02201-01' | '2.2KOHM'    | '1%'         = 'SMC_0201R_H010'     | '(SMC_0201R_C_H010)'                   | 'RES,2.2K,1%,0.05W,0201,-55C TO +125C'                                                  | ''        
 'G155-02870-01' | '287OHM'     | '1%'         = 'SMC_0402R_H016'     | '(SMC_0402R_C_H016)'                   | 'RES,287,1%,0.063W,0402'                                                                | ''        
 'G155-02873-01' | '287KOHM'    | '1%'         = 'SMC_0402R_H016'     | '(SMC_0402R_C_H016)'                   | 'RES,287K,1%,0.0625W,0402'                                                              | ''        
 'G155-01912-01' | '19.1KOHM'   | '1%'         = 'SMC_0402R_H016'     | '(SMC_0402R_C_H016)'                   | 'RES,19.1K,1%,0.063W,0402'                                                              | ''        
 'G155-03653-01' | '365KOHM'    | '1%'         = 'SMC_0402R_H016'     | '(SMC_0402R_C_H016,SMC_0402R_V2_H016)' | 'RES,365K,1%,0.063W,0402'                                                               | ''        
 'G155-01273-01' | '127KOHM'    | '1%'         = 'SMC_0402R_H016'     | '(SMC_0402R_C_H016)'                   | 'RES,127K,1%,0.063W,0402'                                                               | ''        
 'G155-08252-01' | '82.5KOHM'   | '1%'         = 'SMC_0402R_H016'     | '(SMC_0402R_C_H016)'                   | 'RES,82.5K,1%,0.063W,0402'                                                              | ''        
 'G155-039R0-01' | '39OHM'      | '1%'         = 'SMC_0402R_H016'     | '(SMC_0402R_H016)'                     | 'RES,39,1%,0.0625W,0402'                                                                | ''        
 'G155-06491-01' | '6.49KOHM'   | '1%'         = 'SMC_0402R_H016'     | '(SMC_0402R_C_H016,SMC_0402R_V2_H016)' | 'RES,6.49K,1%,0.063W,0402'                                                              | ''        
 'G155-07681-01' | '7.68KOHM'   | '1%'         = 'SMC_0402R'          | '(SMC_0402R_C)'                        | 'RES,7.68K,1%,0.063W,0402'                                                              | ''        
 'G155-00105-05' | '1MOHM'      | '5%'         = 'SMC_0402R_H016'     | '(SMC_0402R_C_H016)'                   | 'RES,TSB,1M,5%,0.063W,0402'                                                             | 'NFND'    
 'G155-05101-01' | '5.1KOHM'    | '1%'         = 'SMC_0402R_H016'     | '(SMC_0402R_C_H016)'                   | 'RES,5.1K,1%,0.063W,0402'                                                               | ''        
 'G155-00106-05' | '10MOHM'     | '5%'         = 'SMC_0402R_H016'     | '(SMC_0402R_C_H016)'                   | 'RES,10M,5%,1/16W,0402'                                                                 | ''        
 'G155-01301-01' | '1.3KOHM'    | '1%'         = 'SMC_0402R_H016'     | '(SMC_0402R_C_H016)'                   | 'RES,1.3K,1%,0.063W,0402'                                                               | ''        
 'G152-10374-01' | '1KOHM'      | '0.1%'       = 'SMC_0402R_H016'     | '(SMC_0402R_C_H016)'                   | 'RES,1K,0.1%,1/16W,0402'                                                                | ''        
 'G155-08873-01' | '887KOHM'    | '1%'         = 'SMC_0402R_H016'     | '(SMC_0402R_C_H016)'                   | 'RES,887K,1%,1/16W,0402'                                                                | ''        
 'G156-03R32-01' | '3.32OHM'    | '1%'         = 'SMC_0603R_H022'     | '(SMC_0603R_H022)'                     | 'RES,3.32 OHM,1%,0.1W,0603'                                                             | ''        
 'G156-05361-01' | '5.36KOHM'   | '1%'         = 'SMC_0603R_H022'     | '(SMC_0603R_H022)'                     | 'RES,5.36K,1%,0.1W,0603'                                                                | ''        
 'G155-09762-01' | '97.6KOHM'   | '1%'         = 'SMC_0402R_H016'     | '(SMC_0402R_C_H016)'                   | 'RES,97.6K,1%,0.063W,0402'                                                              | ''        
 'G156-000R0-01' | '0OHM'       | '1%'         = 'SMC_0603R_H022'     | '(SMC_0603R_H022)'                     | 'RES,0 OHM,1%,1/10W,0603'                                                               | 'NFND'    
 'G152-10375-01' | '0OHM'       | 'NA'         = 'SMC_0603R_H014'     | '(SMC_0603R_H014)'                     | 'RES,0 OHM,0.5M OHM MAX,22.4A,0.25W,0603'                                               | ''        
 'G155-06203-01' | '620KOHM'    | '1%'         = 'SMC_0402R_H016'     | '(SMC_0402R_C_H016)'                   | 'RES,620K,1%,1/16W,0402'                                                                | ''        
 'G152-10386-01' | '2KOHM'      | '1%'         = 'SMC_0402R_H016'     | '(SMC_0402R_C_H016)'                   | 'RES,2K,1%,0.0625W,0402,ASR'                                                            | ''        
 'G152-10385-01' | '20KOHM'     | '1%'         = 'SMC_0402R_H016'     | '(SMC_0402R_C_H016)'                   | 'RES,20K,1%,0.0625W,0402,ASR'                                                           | ''        
 'G152-10384-01' | '10KOHM'     | '1%'         = 'SMC_0201R_H010'     | '(SMC_0201R_C_H010)'                   | 'RES,10K,1%,0.05W,0201,ASR'                                                             | ''        
 'G152-10383-01' | '4.02KOHM'   | '1%'         = 'SMC_0402R_H016'     | '(SMC_0402R_C_H016)'                   | 'RES,4.02K,1%,0.1W,0402,ASR'                                                            | 'OBSOLETE'
 'G152-10382-01' | '100KOHM'    | '1%'         = 'SMC_0402R_H016'     | '(SMC_0402R_C_H016)'                   | 'RES,100K,1%,0.1W,0402,ASR'                                                             | 'OBSOLETE'
 'G152-10381-01' | '0OHM'       | '5%'         = 'SMC_0402R_H016'     | '(SMC_0402R_C_H016)'                   | 'RES,0,5%,0.1W,0402,ASR'                                                                | 'OBSOLETE'
 'G152-10380-01' | '10KOHM'     | '1%'         = 'SMC_0402R_H016'     | '(SMC_0402R_C_H016)'                   | 'RES,10K,1%,0.1W,0402,ASR'                                                              | 'OBSOLETE'
 'G152-10390-01' | '1KOHM'      | '1%'         = 'SMC_0402R_H016'     | '(SMC_0402R_C_H016)'                   | 'RES,1K,1%,0.1W,0402,ASR'                                                               | 'OBSOLETE'
 'G152-10389-01' | '4.7KOHM'    | '1%'         = 'SMC_0402R_H016'     | '(SMC_0402R_C_H016)'                   | 'RES,4.7K,1%,0.1W,0402,ASR'                                                             | 'OBSOLETE'
 'G152-10388-01' | '6.19KOHM'   | '1%'         = 'SMC_0402R_H016'     | '(SMC_0402R_C_H016)'                   | 'RES,6.19K,1%,0.1W,TCR±200,0402,ASR'                                                   | ''        
 'G152-10387-01' | '3.24KOHM'   | '1%'         = 'SMC_0402R_H016'     | '(SMC_0402R_C_H016)'                   | 'RES,3.24K,1%,0.1W,0402,ASR'                                                            | ''        
 'G152-10391-01' | '19.1KOHM'   | '0.1%'       = 'SMC_0402R_H016'     | '(SMC_0402R_C_H016)'                   | 'RES,19.1K,0.1%,0.063W,0402'                                                            | ''        
 'G152-10392-01' | '130KOHM'    | '0.1%'       = 'SMC_0402R_H016'     | '(SMC_0402R_C_H016)'                   | 'RES,130K,0.1%,0.063W,0402,+/-100PPM,1.0MM*0.5MM'                                       | ''        
 'G152-10393-01' | '100KOHM'    | '1%'         = 'SMC_0402R_H016'     | '(SMC_0402R_C_H016)'                   | 'RES,100K,1%,0.1W,75V,0402,ASR'                                                         | ''        
 'G152-10394-01' | '1.54KOHM'   | '1%'         = 'SMC_0402R_H016'     | '(SMC_0402R_C_H016)'                   | 'RES,1.54K,1%,0.063W,0402,ASR'                                                          | ''        
 'G152-10395-01' | '1.1KOHM'    | '1%'         = 'SMC_0402R_H016'     | '(SMC_0402R_C_H016)'                   | 'RES,1.1K,1%,0.063W,0402,ASR'                                                           | ''        
 'G152-10396-01' | '10KOHM'     | '1%'         = 'SMC_0402R_H016'     | '(SMC_0402R_C_H016)'                   | 'RES,10K,1%,0.1W,75V,0402,ASR'                                                          | ''        
 'G152-10397-01' | '33OHM'      | '1%'         = 'SMC_0402R_H016'     | '(SMC_0402R_C_H016)'                   | 'RES,33,1%,0.063W,0402,ASR'                                                             | ''        
 'G152-10398-01' | '75KOHM'     | '1%'         = 'SMC_0402R_H016'     | '(SMC_0402R_C_H016)'                   | 'RES,75K,1%,0.063W,0402,ASR'                                                            | ''        
 'G152-10399-01' | '0.0005OHM'  | '1%'         = 'SMC_2512R_V2'       | '(SMC_2512R_V2)'                       | 'RES,0.0005OHM,1%,2W,2512,ASR'                                                          | ''        
 'G152-10400-01' | '0.001OHM'   | '1%'         = 'SMC_2512R_V2'       | '(SMC_2512R_V2)'                       | 'RES,0.001OHM,1%,2W,2512,ASR'                                                           | ''        
 'G152-10401-01' | '1.0OHM'     | '1%'         = 'SMC_0603R_H022'     | '(SMC_0603R_H022)'                     | 'RES,1.0,1%,0.1W,0603,ASR'                                                              | ''        
 'G152-10402-01' | '0OHM'       | 'NA'         = 'SMC_0603R_H024'     | '(SMC_0603R_H024)'                     | 'RES,0,JUMPER,0.1W,0603,ASR'                                                            | ''        
 'G152-10403-01' | '1.05KOHM'   | '1%'         = 'SMC_0402R_H016'     | '(SMC_0402R_C_H016)'                   | 'RES,1.05K,1%,0.063W,0402,ASR'                                                          | ''        
 'G152-10404-01' | '3.16KOHM'   | '1%'         = 'SMC_0402R_H016'     | '(SMC_0402R_C_H016)'                   | 'RES,3.16K,1%,0.063W,0402,ASR'                                                          | ''        
 'G152-10405-01' | '140OHM'     | '1%'         = 'SMC_0402R_H016'     | '(SMC_0402R_C_H016)'                   | 'RES,140,1%,0.063W,0402,ASR'                                                            | ''        
 'G155-08250-01' | '825OHM'     | '1%'         = 'SMC_0402R_H016'     | '(SMC_0402R_C_H016)'                   | 'RES,825,1%,0.063W,0402'                                                                | ''        
 'G152-10433-01' | '14.7KOHM'   | '1%'         = 'SMC_0402R_H016'     | '(SMC_0402R_C_H016)'                   | 'RES,14.7K,1%,0.063W,0402,ASR'                                                          | ''        
 'G152-10434-01' | '51.1OHM'    | '1%'         = 'SMC_0402R_H016'     | '(SMC_0402R_C_H016)'                   | 'RES,51.1,1%,0.063W,0402,ASR'                                                           | ''        
 'G152-10435-01' | '4.7KOHM'    | '1%'         = 'SMC_0402R_H016'     | '(SMC_0402R_C_H016)'                   | 'RES,4.7K,1%,0.1W,200PPM,0402,ASR'                                                      | ''        
 'G152-10437-01' | '5.9KOHM'    | '1%'         = 'SMC_0402R_H016'     | '(SMC_0402R_C_H016)'                   | 'RES,5.9K,1%,0.063W,0402,ASR'                                                           | ''        
 'G152-10438-01' | '60.4KOHM'   | '1%'         = 'SMC_0402R_H016'     | '(SMC_0402R_C_H016)'                   | 'RES,60.4K,1%,0.063W,0402,ASR'                                                          | ''        
 'G152-10439-01' | '90.9OHM'    | '1%'         = 'SMC_0402R_H016'     | '(SMC_0402R_C_H016)'                   | 'RES,90.9,1%,0.063W,0402,ASR'                                                           | ''        
 'G152-10440-01' | '40.2KOHM'   | '1%'         = 'SMC_0402R_H016'     | '(SMC_0402R_C_H016)'                   | 'RES,40.2K,1%,0.063W,0402,ASR'                                                          | ''        
 'G152-10441-01' | '200KOHM'    | '1%'         = 'SMC_0402R_H016'     | '(SMC_0402R_C_H016)'                   | 'RES,200K,1%,0.063W,0402,ASR'                                                           | ''        
 'G152-10442-01' | '348OHM'     | '1%'         = 'SMC_0402R_H016'     | '(SMC_0402R_C_H016)'                   | 'RES,348,1%,0.063W,0402,ASR'                                                            | ''        
 'G152-10406-01' | '53.6KOHM'   | '1%'         = 'SMC_0402R_H016'     | '(SMC_0402R_C_H016)'                   | 'RES,53.6K,1%,0.063W,0402,ASR'                                                          | ''        
 'G152-10408-01' | '75OHM'      | '1%'         = 'SMC_0402R_H016'     | '(SMC_0402R_C_H016)'                   | 'RES,75,1%,0.063W,0402,ASR'                                                             | ''        
 'G152-10410-01' | '64.9OHM'    | '1%'         = 'SMC_0402R_H016'     | '(SMC_0402R_C_H016)'                   | 'RES,64.9,1%,0.063W,0402,ASR'                                                           | ''        
 'G152-10412-01' | '953OHM'     | '1%'         = 'SMC_0402R_H016'     | '(SMC_0402R_C_H016)'                   | 'RES,953,1%,0.063W,0402,ASR'                                                            | ''        
 'G152-10420-01' | '75KOHM'     | '1%'         = 'SMC_0603R_H024'     | '(SMC_0603R_H024)'                     | 'RES,75K,1%,0.1W,0603,ASR'                                                              | ''        
 'G152-10443-01' | '57.6KOHM'   | '1%'         = 'SMC_0402R_H016'     | '(SMC_0402R_C_H016)'                   | 'RES,57.6K,1%,0.063W,0402,ASR'                                                          | ''        
 'G152-10445-01' | '6.2KOHM'    | '1%'         = 'SMC_0402R_H016'     | '(SMC_0402R_C_H016)'                   | 'RES,6.2K,1%,0.063W,0402,ASR'                                                           | ''        
 'G152-10448-01' | '80.6OHM'    | '1%'         = 'SMC_0402R_H016'     | '(SMC_0402R_C_H016)'                   | 'RES,80.6,1%,0.063W,0402,ASR'                                                           | ''        
 'G152-10469-01' | '71.5KOHM'   | '1%'         = 'SMC_0402R_H016'     | '(SMC_0402R_C_H016)'                   | 'RES,71.5K,1%,0.063W,0402,ASR'                                                          | ''        
 'G152-10475-01' | '66.5KOHM'   | '1%'         = 'SMC_0402R_H016'     | '(SMC_0402R_C_H016)'                   | 'RES,66.5K,1%,0.063W,0402,ASR'                                                          | ''        
 'G152-10407-01' | '47.5OHM'    | '1%'         = 'SMC_0402R_H016'     | '(SMC_0402R_C_H016)'                   | 'RES,47.5,1%,0.063W,0402,ASR'                                                           | ''        
 'G152-10409-01' | '37.4KOHM'   | '1%'         = 'SMC_0402R_H016'     | '(SMC_0402R_C_H016)'                   | 'RES,37.4K,1%,0.063W,0402,ASR'                                                          | ''        
 'G152-10411-01' | '4.02KOHM'   | '1%'         = 'SMC_0402R_H016'     | '(SMC_0402R_C_H016)'                   | 'RES,4.02K,1%,0.1W,75V,0402,ASR'                                                        | ''        
 'G152-10419-01' | '52.3KOHM'   | '0.1%'       = 'SMC_0402R_H016'     | '(SMC_0402R_C_H016)'                   | 'RES,52.3K,0.1%,0.063W,0402,ASR'                                                        | ''        
 'G152-10427-01' | '47KOHM'     | '1%'         = 'SMC_0402R_H016'     | '(SMC_0402R_C_H016)'                   | 'RES,47K,1%,0.063W,0402,ASR'                                                            | ''        
 'G152-10429-01' | '43OHM'      | '1%'         = 'SMC_0402R_H016'     | '(SMC_0402R_C_H016)'                   | 'RES,43,1%,0.063W,0402,ASR'                                                             | ''        
 'G152-10450-01' | '51.1KOHM'   | '1%'         = 'SMC_0402R_H016'     | '(SMC_0402R_C_H016)'                   | 'RES,51.1K,1%,0.063W,0402,ASR'                                                          | ''        
 'G152-10453-01' | '4.99KOHM'   | '1%'         = 'SMC_0402R_H016'     | '(SMC_0402R_C_H016)'                   | 'RES,4.99K,1%,0.063W,0402,ASR'                                                          | ''        
 'G152-10462-01' | '475KOHM'    | '1%'         = 'SMC_0402R_H016'     | '(SMC_0402R_C_H016)'                   | 'RES,475K,1%,0.063W,0402,ASR'                                                           | ''        
 'G152-10470-01' | '39.2KOHM'   | '1%'         = 'SMC_0402R_H016'     | '(SMC_0402R_C_H016)'                   | 'RES,39.2K,1%,0.063W,0402,ASR'                                                          | ''        
 'G152-10474-01' | '49.9KOHM'   | '1%'         = 'SMC_0402R_H016'     | '(SMC_0402R_C_H016)'                   | 'RES,49.9K,1%,0.063W,0402,ASR'                                                          | ''        
 'G152-10477-01' | '806OHM'     | '1%'         = 'SMC_0402R_H016'     | '(SMC_0402R_C_H016)'                   | 'RES,806,1%,0.063W,0402,ASR'                                                            | ''        
 'G152-10479-01' | '422OHM'     | '1%'         = 'SMC_0402R_H016'     | '(SMC_0402R_C_H016)'                   | 'RES,422,1%,1/16W,0402,ASR'                                                             | ''        
 'G152-10480-01' | '4.99KOHM'   | '0.1%'       = 'SMC_0402R_H016'     | '(SMC_0402R_C_H016)'                   | 'RES,4.99K,0.1%,0.063W,25V,-55~+125C,0402,ASR'                                          | ''        
 'G152-10415-01' | '22.6KOHM'   | '1%'         = 'SMC_0402R_H016'     | '(SMC_0402R_C_H016)'                   | 'RES,22.6K,1%,0.063W,0402,ASR'                                                          | ''        
 'G152-10422-01' | '200OHM'     | '1%'         = 'SMC_0402R_H016'     | '(SMC_0402R_C_H016)'                   | 'RES,200,1%,0.2W,0402,ASR'                                                              | ''        
 'G152-10428-01' | '24KOHM'     | '1%'         = 'SMC_0402R_H016'     | '(SMC_0402R_C_H016)'                   | 'RES,24K,1%,0.063W,0402,ASR'                                                            | ''        
 'G152-10430-01' | '27OHM'      | '1%'         = 'SMC_0402R_H016'     | '(SMC_0402R_C_H016)'                   | 'RES,27,1%,0.063W,0402,ASR'                                                             | ''        
 'G152-10431-01' | '20OHM'      | '1%'         = 'SMC_0402R_H016'     | '(SMC_0402R_C_H016)'                   | 'RES,20,1%,0.063W,0402,ASR'                                                             | ''        
 'G152-10444-01' | '30.9KOHM'   | '1%'         = 'SMC_0402R_H016'     | '(SMC_0402R_C_H016)'                   | 'RES,30.9K,1%,0.063W,0402,ASR'                                                          | ''        
 'G152-10451-01' | '3.92KOHM'   | '1%'         = 'SMC_0402R_H016'     | '(SMC_0402R_C_H016)'                   | 'RES,3.92K,1%,0.063W,0402,ASR'                                                          | ''        
 'G152-10454-01' | '33.2KOHM'   | '1%'         = 'SMC_0402R_H016'     | '(SMC_0402R_C_H016)'                   | 'RES,33.2K,1%,0.063W,0402,ASR'                                                          | ''        
 'G152-10458-01' | '220OHM'     | '1%'         = 'SMC_0402R_H016'     | '(SMC_0402R_C_H016)'                   | 'RES,220,1%,0.063W,0402,ASR'                                                            | ''        
 'G152-10463-01' | '240OHM'     | '1%'         = 'SMC_0402R_H016'     | '(SMC_0402R_C_H016)'                   | 'RES,240,1%,0.063W,0402,ASR'                                                            | ''        
 'G152-10466-01' | '21KOHM'     | '1%'         = 'SMC_0402R_H016'     | '(SMC_0402R_C_H016)'                   | 'RES,21K,1%,0.063W,0402,ASR'                                                            | ''        
 'G152-10467-01' | '23.2KOHM'   | '1%'         = 'SMC_0402R_H016'     | '(SMC_0402R_C_H016)'                   | 'RES,23.2K,1%,0.063W,0402,ASR'                                                          | ''        
 'G152-10468-01' | '249KOHM'    | '1%'         = 'SMC_0402R_H016'     | '(SMC_0402R_C_H016)'                   | 'RES,249K,1%,0.063W,0402,ASR'                                                           | ''        
 'G152-10471-01' | '31.6KOHM'   | '1%'         = 'SMC_0402R_H016'     | '(SMC_0402R_C_H016)'                   | 'RES,31.6K,1%,0.063W,0402,ASR'                                                          | ''        
 'G152-10476-01' | '274OHM'     | '1%'         = 'SMC_0402R_H016'     | '(SMC_0402R_C_H016)'                   | 'RES,274,1%,0.063W,0402,ASR'                                                            | ''        
 'G152-10482-01' | '3.83KOHM'   | '1%'         = 'SMC_0402R_H016'     | '(SMC_0402R_C_H016)'                   | 'RES,3.83K,1%,0.063W,0402,ASR'                                                          | ''        
 'G152-10481-01' | '2.2OHM'     | '5%'         = 'SMC_0603R_H024'     | '(SMC_0603R_H024)'                     | 'RES,2.2,5%,0.1W,50V,0603,ASR'                                                          | ''        
 'G152-10478-01' | '1.5KOHM'    | '1%'         = 'SMC_0402R_H016'     | '(SMC_0402R_C_H016)'                   | 'RES,1.5K,1%,0.063W,0402,ASR'                                                           | ''        
 'G152-10473-01' | '115KOHM'    | '1%'         = 'SMC_0402R_H016'     | '(SMC_0402R_C_H016)'                   | 'RES,115K,1%,0.063W,0402,ASR'                                                           | ''        
 'G152-10472-01' | '100OHM'     | '1%'         = 'SMC_0402R_H016'     | '(SMC_0402R_C_H016)'                   | 'RES,100,1%,0.063W,0402,ASR'                                                            | ''        
 'G152-10465-01' | '169KOHM'    | '1%'         = 'SMC_0402R_H016'     | '(SMC_0402R_C_H016)'                   | 'RES,169K,1%,0.063W,0402,ASR'                                                           | ''        
 'G152-10464-01' | '110KOHM'    | '1%'         = 'SMC_0402R_H016'     | '(SMC_0402R_C_H016)'                   | 'RES,110K,1%,0.063W,0402,ASR'                                                           | ''        
 'G152-10461-01' | '154KOHM'    | '1%'         = 'SMC_0402R_H016'     | '(SMC_0402R_C_H016)'                   | 'RES,154K,1%,0.063W,0402,ASR'                                                           | ''        
 'G152-10460-01' | '2.55KOHM'   | '1%'         = 'SMC_0402R_H016'     | '(SMC_0402R_C_H016)'                   | 'RES,2.55K,1%,0.063W,0402,ASR'                                                          | ''        
 'G152-10459-01' | '2.87KOHM'   | '0.1%'       = 'SMC_0402R_H016'     | '(SMC_0402R_C_H016)'                   | 'RES,2.87K,0.1%,0.063W,0402,ASR'                                                        | ''        
 'G152-10457-01' | '13KOHM'     | '1%'         = 'SMC_0402R_H016'     | '(SMC_0402R_C_H016)'                   | 'RES,13K,1%,0.063W,0402,ASR'                                                            | ''        
 'G152-10456-01' | '1KOHM'      | '1%'         = 'SMC_0402R_H016'     | '(SMC_0402R_C_H016)'                   | 'RES,1K,1%,0.1W,75V,0402,ASR'                                                           | ''        
 'G152-10455-01' | '100OHM'     | '1%'         = 'SMC_0402R_H016'     | '(SMC_0402R_C_H016)'                   | 'RES,100,1%,0.063W,0402,ASR'                                                            | ''        
 'G152-10452-01' | '10OHM'      | '1%'         = 'SMC_0402R_H016'     | '(SMC_0402R_C_H016)'                   | 'RES,10,1%,0.063W,0402,ASR'                                                             | ''        
 'G152-10449-01' | '2.7KOHM'    | '1%'         = 'SMC_0402R_H016'     | '(SMC_0402R_C_H016)'                   | 'RES,2.7K,1%,0.063W,0402,ASR'                                                           | ''        
 'G152-10447-01' | '10KOHM'     | '5%'         = 'SMC_0402R_H016'     | '(SMC_0402R_C_H016)'                   | 'RES,10K,5%,0.063W,0402,ASR'                                                            | ''        
 'G152-10446-01' | '11.3KOHM'   | '1%'         = 'SMC_0402R_H016'     | '(SMC_0402R_C_H016)'                   | 'RES,11.3K,1%,0.063W,0402,ASR'                                                          | ''        
 'G152-10436-01' | '10MOHM'     | '1%'         = 'SMC_0402R_H016'     | '(SMC_0402R_C_H016)'                   | 'RES,10M,1%,0.063W,0402,ASR'                                                            | ''        
 'G152-10432-01' | '169OHM'     | '1%'         = 'SMC_0402R_H016'     | '(SMC_0402R_C_H016)'                   | 'RES,169,1%,0.063W,0402,ASR'                                                            | ''        
 'G152-10426-01' | '15KOHM'     | '1%'         = 'SMC_0402R_H016'     | '(SMC_0402R_C_H016)'                   | 'RES,15K,1%,0.063W,0402,ASR'                                                            | ''        
 'G152-10425-01' | '196KOHM'    | '1%'         = 'SMC_0402R_H016'     | '(SMC_0402R_C_H016)'                   | 'RES,196K,1%,0.063W,0402,ASR'                                                           | ''        
 'G152-10424-01' | '20OHM'      | '0.1%'       = 'SMC_0402R_H016'     | '(SMC_0402R_C_H016)'                   | 'RES,20,0.1%,0.063W,0402,ASR'                                                           | ''        
 'G152-10423-01' | '2.94KOHM'   | '0.1%'       = 'SMC_0402R_H016'     | '(SMC_0402R_C_H016)'                   | 'RES,2.94K,0.1%,0.063W,0402,ASR'                                                        | ''        
 'G152-10421-01' | '1.91KOHM'   | '0.1%'       = 'SMC_0402R_H016'     | '(SMC_0402R_C_H016)'                   | 'RES,1.91K,0.1%,0.063W,0402,ASR'                                                        | ''        
 'G152-10418-01' | '100KOHM'    | '1%'         = 'SMC_0603R_H024'     | '(SMC_0603R_H024)'                     | 'RES,100K,1%,0.1W,0603,ASR'                                                             | ''        
 'G152-10417-01' | '120OHM'     | '1%'         = 'SMC_0402R_H016'     | '(SMC_0402R_C_H016)'                   | 'RES,120,1%,0.063W,0402,ASR'                                                            | ''        
 'G152-10416-01' | '17.4KOHM'   | '1%'         = 'SMC_0402R_H016'     | '(SMC_0402R_C_H016)'                   | 'RES,17.4K,1%,0.063W,0402,ASR'                                                          | ''        
 'G152-10414-01' | '2.74KOHM'   | '1%'         = 'SMC_0402R_H016'     | '(SMC_0402R_C_H016)'                   | 'RES,2.74K,1%,0.063W,0402,ASR'                                                          | ''        
 'G152-10413-01' | '150KOHM'    | '1%'         = 'SMC_0402R_H016'     | '(SMC_0402R_C_H016)'                   | 'RES,150K,1%,0.063W,0402,ASR'                                                           | ''        
 'G152-10487-01' | '5.36KOHM'   | '1%'         = 'SMC_0402R_H016'     | '(SMC_0402R_C_H016)'                   | 'RES,5.36K,1%,0.063W,0402,ASR'                                                          | ''        
 'G152-10488-01' | '8.2KOHM'    | '1%'         = 'SMC_0402R_H016'     | '(SMC_0402R_C_H016)'                   | 'RES,8.2K,1%,0.063W,0402,ASR'                                                           | ''        
 'G152-10489-01' | '475OHM'     | '1%'         = 'SMC_0402R_H016'     | '(SMC_0402R_C_H016)'                   | 'RES,475,1%,0.063W,0402,ASR'                                                            | ''        
 'G152-10490-01' | '2KOHM'      | '1%'         = 'SMC_0402R_H016'     | '(SMC_0402R_C_H016)'                   | 'RES,2K,1%,0.063W,0402,ASR'                                                             | ''        
 'G152-10491-01' | '470OHM'     | '1%'         = 'SMC_0402R_H016'     | '(SMC_0402R_C_H016)'                   | 'RES,470,1%,0.063W,0402,ASR'                                                            | ''        
 'G152-10492-01' | '1.2KOHM'    | '1%'         = 'SMC_0402R_H016'     | '(SMC_0402R_C_H016)'                   | 'RES,1.2K,1%,0.063W,0402,ASR'                                                           | ''        
 'G152-10498-01' | '22OHM'      | '1%'         = 'SMC_0402R_H016'     | '(SMC_0402R_C_H016)'                   | 'RES,22,1%,0.063W,0402,ASR'                                                             | ''        
 'G152-10499-01' | '330OHM'     | '1%'         = 'SMC_0402R_H016'     | '(SMC_0402R_C_H016)'                   | 'RES,330,1%,0.063W,0402,ASR'                                                            | ''        
 'G152-10500-01' | '113OHM'     | '1%'         = 'SMC_0402R_H016'     | '(SMC_0402R_C_H016)'                   | 'RES,113,1%,0.063W,0402,ASR'                                                            | ''        
 'G152-10501-01' | '143KOHM'    | '1%'         = 'SMC_0402R_H016'     | '(SMC_0402R_C_H016)'                   | 'RES,143K,1%,0.063W,0402,ASR'                                                           | ''        
 'G152-10502-01' | '6.49KOHM'   | '0.1%'       = 'SMC_0402R_H016'     | '(SMC_0402R_C_H016)'                   | 'RES,6.49K,0.1%,0.063W,25V,-55~+125C,0402,ASR'                                          | ''        
 'G152-10503-01' | '1MOHM'      | '1%'         = 'SMC_0402R_H016'     | '(SMC_0402R_C_H016)'                   | 'RES,1M,1%,0.063W,0402,ASR'                                                             | ''        
 'G152-10504-01' | '3.3KOHM'    | '1%'         = 'SMC_0402R_H016'     | '(SMC_0402R_C_H016)'                   | 'RES,3.3K,1%,0.063W,0402,ASR'                                                           | ''        
 'G152-10505-01' | '1.2KOHM'    | '0.1%'       = 'SMC_0402R_H016'     | '(SMC_0402R_C_H016)'                   | 'RES,1.2K,0.1%,0.063W,25V,-55~+125C,0402,ASR'                                           | ''        
 'G152-10506-01' | '20KOHM'     | '1%'         = 'SMC_0402R_H016'     | '(SMC_0402R_C_H016)'                   | 'RES,20K,1%,0.063W,0402,ASR'                                                            | ''        
 'G152-10507-01' | '249OHM'     | '1%'         = 'SMC_0402R_H016'     | '(SMC_0402R_C_H016)'                   | 'RES,249,1%,0.063W,0402,ASR'                                                            | ''        
 'G152-10508-01' | '2.2KOHM'    | '1%'         = 'SMC_0402R_H016'     | '(SMC_0402R_C_H016)'                   | 'RES,2.2K,1%0.063W,0402,ASR'                                                            | ''        
 'G152-10509-01' | '2.4KOHM'    | '1%'         = 'SMC_0402R_H016'     | '(SMC_0402R_C_H016)'                   | 'RES,2.4K,1%,0.063W,0402,ASR'                                                           | ''        
 'G152-10510-01' | '150OHM'     | '1%'         = 'SMC_0402R_H016'     | '(SMC_0402R_C_H016)'                   | 'RES,150,1%,0.063W,0402,ASR'                                                            | ''        
 'G152-10511-01' | '20KOHM'     | '1%'         = 'SMC_0402R_H016'     | '(SMC_0402R_C_H016)'                   | 'RES,20K,1%,0.063W,0402,ASR'                                                            | 'REJECTED'
 'G152-10497-01' | '49.9OHM'    | '1%'         = 'SMC_0402R_H016'     | '(SMC_0402R_C_H016)'                   | 'RES,49.9,1%,0.063W,0402,ASR'                                                           | ''        
 'G152-10496-01' | '10KOHM'     | '0.1%'       = 'SMC_0402R_H016'     | '(SMC_0402R_C_H016)'                   | 'RES,10K,0.1%,0.063W,25V,±50PPM,0402,ASR'                                              | ''        
 'G152-10495-01' | '10OHM'      | '5%'         = 'SMC_0603R_H024'     | '(SMC_0603R_H024)'                     | 'RES,10,5%,0.1W,-200~+400PPM,0603,ASR'                                                  | ''        
 'G152-10494-01' | '2MOHM'      | '1%'         = 'SMC_0402R_H016'     | '(SMC_0402R_C_H016)'                   | 'RES,2M,1%,0.063W,±200PPM,0402,ASR'                                                    | ''        
 'G152-10493-01' | '14.3KOHM'   | '0.1%'       = 'SMC_0402R_H016'     | '(SMC_0402R_C_H016)'                   | 'RES,14.3K,0.1%,0.063W,25V,-55~+125C,±50PPM,0402,ASR'                                  | ''        
 'G152-10486-01' | '43.2KOHM'   | '1%'         = 'SMC_0402R_H016'     | '(SMC_0402R_C_H016)'                   | 'RES,43.2K,1%,0.063W,0402,ASR'                                                          | ''        
 'G152-10485-01' | '22.1KOHM'   | '1%'         = 'SMC_0402R_H016'     | '(SMC_0402R_C_H016)'                   | 'RES,22.1K,1%,0.063W,0402,ASR'                                                          | ''        
 'G152-10484-01' | '9.76KOHM'   | '1%'         = 'SMC_0402R_H016'     | '(SMC_0402R_C_H016)'                   | 'RES,9.76K,1%,0.063W,0402,ASR'                                                          | ''        
 'G152-10483-01' | '73.2KOHM'   | '1%'         = 'SMC_0402R_H016'     | '(SMC_0402R_C_H016)'                   | 'RES,73.2K,1%,0.063W,0402,ASR'                                                          | ''        
 'G152-10512-01' | '1.0OHM'     | '1%'         = 'SMC_0402R_H016'     | '(SMC_0402R_C_H016)'                   | 'RES,1.0,1%,0.063W,-200~+400PPM,0402,ASR'                                               | ''        
 'G152-10513-01' | '2.2OHM'     | '5%'         = 'SMC_0402R_H016'     | '(SMC_0402R_C_H016)'                   | 'RES,2.2,5%,0.063W,200PPM,0402,ASR'                                                     | ''        
 'G152-10514-01' | '1.0OHM'     | '5%'         = 'SMC_0805R_H026'     | '(SMC_0805R_H026)'                     | 'RES,1.0,5%,0.125W,-200~+400PPM,0805,ASR'                                               | ''        
 'G152-10515-01' | '2.2OHM'     | '1%'         = 'SMC_0402R_H016'     | '(SMC_0402R_C_H016)'                   | 'RES,2.2,1%,0.063W,200PPM,0402,ASR'                                                     | ''        
 'G152-10516-01' | '8.87KOHM'   | '0.1%'       = 'SMC_0402R_H016'     | '(SMC_0402R_C_H016)'                   | 'RES,8.87K,0.1%,0.063W,25V,50PPM,0402,ASR'                                              | ''        
 'G152-10517-01' | '2.8KOHM'    | '0.1%'       = 'SMC_0402R_H016'     | '(SMC_0402R_C_H016)'                   | 'RES,2.8K,0.1%,0.063W,25V,0402,ASR'                                                     | ''        
 'G152-10518-01' | '1.1KOHM'    | '0.1%'       = 'SMC_0402R_H016'     | '(SMC_0402R_C_H016)'                   | 'RES,1.1K,0.1%,0.063W,25V,50PPM,0402,ASR'                                               | ''        
 'G152-10519-01' | '1KOHM'      | '1%'         = 'SMC_0603R_H024'     | '(SMC_0603R_H024)'                     | 'RES,1K,1%,0.1W,50V,0603,ASR'                                                           | ''        
 'G152-10520-01' | '150OHM'     | '1%'         = 'SMC_0603R_H024'     | '(SMC_0603R_H024)'                     | 'RES,150,1%,0.1W,50V,0603,ASR'                                                          | ''        
 'G152-10521-01' | '0OHM'       | 'NA'         = 'SMC_0402R_H016'     | '(SMC_0402R_C_H016)'                   | 'RES,0,JUMPER,0.1W,75V,0402,ASR'                                                        | ''        
 'G152-10522-01' | '0OHM'       | 'NA'         = 'SMC_0805R_H026'     | '(SMC_0805R_H026)'                     | 'RES,0,JUMPER,0.125W,0805,ASR'                                                          | ''        
 'G152-10523-01' | '1.93KOHM'   | '0.1%'       = 'SMC_0603R_H022'     | '(SMC_0603R_H022)'                     | 'RES,1.93K,0.1%,0.063W,50V,0603,ASR'                                                    | ''        
 'G152-10524-01' | '4.7KOHM'    | '0.1%'       = 'SMC_0402R_H016'     | '(SMC_0402R_C_H016)'                   | 'RES,4.7K,0.1%,0.063W,25V,50PPM,0402,ASR'                                               | ''        
 'G152-10525-01' | '120OHM'     | '1%'         = 'SMC_0603R_H024'     | '(SMC_0603R_H024)'                     | 'RES,120,1%,0.1W,50V,0603,ASR'                                                          | ''        
 'G152-10526-01' | '1.65KOHM'   | '0.1%'       = 'SMC_0402R_H016'     | '(SMC_0402R_C_H016)'                   | 'RES,1.65K,0.1%,0.063W,25V,50PPM,0402,ASR'                                              | ''        
 'G152-10527-01' | '1.0KOHM'    | '0.1%'       = 'SMC_0402R_H016'     | '(SMC_0402R_C_H016)'                   | 'RES,1.0K,0.1%,0.063W,25V,-55~+125C,±50PPM,0402,ASR'                                   | ''        
 'G152-10528-01' | '2OHM'       | '1%'         = 'SMC_1210R_H024'     | '(SMC_1210R_H024)'                     | 'RES,2OHM,1%,0.5W,1210,ASR'                                                             | ''        
 'G152-10534-01' | '4.32KOHM'   | '1%'         = 'SMC_0402R_H016'     | '(SMC_0402R_C_H016)'                   | 'RES,4.32K,1%,0.063W,0402,ASR'                                                          | ''        
 'G152-10533-01' | '47.5KOHM'   | '1%'         = 'SMC_0402R_H016'     | '(SMC_0402R_C_H016)'                   | 'RES,47.5K,1%,0.063W,0402,ASR'                                                          | ''        
 'G152-10532-01' | '3.32KOHM'   | '1%'         = 'SMC_0402R_H016'     | '(SMC_0402R_C_H016)'                   | 'RES,3.32K,1%,0.063W,0402,ASR'                                                          | ''        
 'G152-10531-01' | '8.06KOHM'   | '1%'         = 'SMC_0402R_H016'     | '(SMC_0402R_C_H016)'                   | 'RES,8.06K,1%,0.063W,0402,ASR'                                                          | ''        
 'G152-10530-01' | '732KOHM'    | '1%'         = 'SMC_0402R_H016'     | '(SMC_0402R_C_H016)'                   | 'RES,732K,1%,0.063W,0402,ASR'                                                           | ''        
 'G152-10529-01' | '11.0KOHM'   | '1%'         = 'SMC_0402R_H016'     | '(SMC_0402R_C_H016)'                   | 'RES,11.0K,1%,0.063W,0402,ASR'                                                          | ''        
 'G152-10535-01' | '2KOHM'      | '1%'         = 'SMC_0603R_H024'     | '(SMC_0603R_H024)'                     | 'RES,2K,1%,0.1W,0603,50V,ASR'                                                           | ''        
 'G152-10536-01' | '20.0OHM'    | '1%'         = 'SMC_0603R_H024'     | '(SMC_0603R_H024)'                     | 'RES,20.0,1%,0.1W,0603,50V,ASR'                                                         | ''        
 'G152-10538-01' | '10OHM'      | '1%'         = 'SMC_1206R_H026'     | '(SMC_1206R_H026)'                     | 'RES,10OHM,1%,0.75W,1206,ASR'                                                           | ''        
 'G152-10537-01' | '6.8KOHM'    | '1%'         = 'SMC_0402R_H016'     | '(SMC_0402R_C_H016)'                   | 'RES,6.8K,1%,0.0625W,0402,25V,ASR'                                                      | ''        
 'G152-10539-01' | '2.2OHM'     | '5%'         = 'SMC_0805R_H026'     | '(SMC_0805R_H026)'                     | 'RES,2.2,5%,0.125W,0805,-200~+400PPM,ASR'                                               | ''        
 'G152-10173-01' | '2.21KOHM'   | '0.1%'       = 'SMC_0402R_H016'     | '(SMC_0402R_C_H016)'                   | 'RES,2.21K,0.1%,0.063W,0402'                                                            | ''        
 'G152-10540-01' | '12.4KOHM'   | '0.1%'       = 'SMC_0402R_H016'     | '(SMC_0402R_C_H016)'                   | 'RES,12.4K,0.1%,0.063W,0402'                                                            | ''        
 'G155-00472-05' | '4.7KOHM'    | '5%'         = 'SMC_0402R_H016'     | '(SMC_0402R_C_H016)'                   | 'RES,4.7KOHM,5%,1/16W,0402'                                                             | 'REJECTED'
 'G152-10544-01' | '10OHM'      | '0.1%'       = 'SMC_0402R_H014'     | '(SMC_0402R_C_H014)'                   | 'RES,10OHM,0.1%,1/16W,0402'                                                             | ''        
 'G152-10543-01' | '27KOHM'     | '0.1%'       = 'SMC_0402R_H016'     | '(SMC_0402R_C_H016)'                   | 'RES,27KOHM,0.1%,1/16W,25PPM/C,0402'                                                    | ''        
 'G152-10542-01' | '2.43KOHM'   | '0.1%'       = 'SMC_0402R_H016'     | '(SMC_0402R_C_H016)'                   | 'RES,2.43KOHM,0.1%,1/16W,0402'                                                          | ''        
 'G152-10541-01' | '27.4KOHM'   | '0.1%'       = 'SMC_0402R_H016'     | '(SMC_0402R_C_H016)'                   | 'RES,27.4KOHM,0.1%,1/16W,0402'                                                          | ''        
 'G152-10547-01' | '41.2KOHM'   | '0.1%'       = 'SMC_0402R_H014'     | '(SMC_0402R_C_H014)'                   | 'RES,41.2KOHM,0.1%,1/16W,0402'                                                          | ''        
 'G152-10546-01' | '174KOHM'    | '0.1%'       = 'SMC_0402R_H016'     | '(SMC_0402R_C_H016)'                   | 'RES,174KOHM,0.1%,1/16W,0402'                                                           | ''        
 'G152-10545-01' | '6.49KOHM'   | '0.1%'       = 'SMC_0402R_H016'     | '(SMC_0402R_C_H016)'                   | 'RES,6.49KOHM,0.1%,1/16W,0402'                                                          | ''        
 'G154-036R0-01' | '36OHM'      | '1%'         = 'SMC_0201R_H010'     | '(SMC_0201R_C_H010)'                   | 'RES,36,1%,0.05W,0201,-55C TO +125C'                                                    | ''        
 'G155-05492-01' | '54.9KOHM'   | '1%'         = 'SMC_0402R_H016'     | '(SMC_0402R_C_H016)'                   | 'RES,54.9K,1%,0.063W,0402'                                                              | ''        
 'G156-01005-01' | '10MOHM'     | '1%'         = 'SMC_0603R_H024'     | '(SMC_0603R_H024)'                     | 'RES,10M,1%,0.1W,0603'                                                                  | ''        
 'G155-03010-01' | '301OHM'     | '1%'         = 'SMC_0402R_H016'     | '(SMC_0402R_C_H016)'                   | 'RES,301,1%,0.0625W,0402'                                                               | ''        
 'G155-03090-01' | '309OHM'     | '1%'         = 'SMC_0402R_H016'     | '(SMC_0402R_C_H016)'                   | 'RES,309,1%,0.063W,0402'                                                                | ''        
 'G155-00470-05' | '47OHM'      | '5%'         = 'SMC_0402R_H016'     | '(SMC_0402R_C_H016)'                   | 'RES,47,5%,0.125W,0402'                                                                 | ''        
 'G155-07872-01' | '78.7KOHM'   | '1%'         = 'SMC_0402R_H016'     | '(SMC_0402R_C_H016)'                   | 'RES,78.7K,1%,0.063W,0402'                                                              | ''        
 'G152-10548-01' | '13.7KOHM'   | '0.1%'       = 'SMC_0402R_H016'     | '(SMC_0402R_C_H016)'                   | 'RES,13.7K,0.1%,0.063W,0402'                                                            | ''        
 'G155-05002-01' | '50KOHM'     | '1%'         = 'SMC_0402R_H016'     | '(SMC_0402R_C_H016)'                   | 'RES,50KOHM,0.1W,1%,0402'                                                               | ''        
 'G154-01002-01' | '10KOHM'     | '1%'         = 'SMC_0201R_H010'     | '(SMC_0201R_C_H010)'                   | 'RES,10K,1%,1/20W,0201,-55C TO +125C'                                                   | ''        
 'G152-10549-01' | '38.8KOHM'   | '0.1%'       = 'SMC_0603R_H022'     | '(SMC_0603R_H022)'                     | 'RES,38.8K,0.1%,0.1W,0603'                                                              | ''        
 'G154-01052-01' | '10.5KOHM'   | '1%'         = 'SMC_0201R_H010'     | '(SMC_0201R_C_H010)'                   | 'RES,10.5K,1%,1/20W,0201'                                                               | ''        
 'G155-062R0-01' | '62OHM'      | '1%'         = 'SMC_0402R_H016'     | '(SMC_0402R_C_H016)'                   | 'RES,62,1%,0.063W,50V,0402'                                                             | ''        
 'G154-01471-01' | '1.47KOHM'   | '1%'         = 'SMC_0201R_H010'     | '(SMC_0201R_C_H010)'                   | 'RES,1.47K,1%,0.05W,0201,-55 TO 155'                                                    | ''        
 'G152-10550-01' | '20.5KOHM'   | '0.1%'       = 'SMC_0402R_H016'     | '(SMC_0402R_C_H016)'                   | 'RES,20.5K,0.1%,0.063W,0402'                                                            | ''        
 'G152-10551-01' | '38.3KOHM'   | '0.1%'       = 'SMC_0402R_H016'     | '(SMC_0402R_C_H016)'                   | 'RES,38.3K,0.1%,0.063W,0402'                                                            | ''        
 'G152-10552-01' | '19.6KOHM'   | '0.1%'       = 'SMC_0402R_H016'     | '(SMC_0402R_C_H016)'                   | 'RES,19.6K,0.1%,0.063W,0402'                                                            | ''        
 'G152-10553-01' | '3.01KOHM'   | '0.1%'       = 'SMC_0402R_H016'     | '(SMC_0402R_C_H016)'                   | 'RES,3.01K,0.1%,0.063W,0402'                                                            | ''        
 'G152-10554-01' | '1.96KOHM'   | '0.1%'       = 'SMC_0402R_H016'     | '(SMC_0402R_C_H016)'                   | 'RES,1.96K,0.1%,0.063W,0402'                                                            | ''        
 'G152-10555-01' | '1.43KOHM'   | '0.1%'       = 'SMC_0402R_H016'     | '(SMC_0402R_C_H016)'                   | 'RES,1.43K,0.1%,0.063W,0402'                                                            | ''        
 'G152-10556-01' | '8.2KOHM'    | '1%'         = 'SMC_0402R_H016'     | '(SMC_0402R_C_H016)'                   | 'RES,8.2K,1%,0.1W,50V,0402,ASR'                                                         | ''        
 'G152-10557-01' | '5.6KOHM'    | '1%'         = 'SMC_0402R_H016'     | '(SMC_0402R_C_H016)'                   | 'RES,5.6K,1%,0.1W,50V,0402,ASR'                                                         | ''        
 'G152-10558-01' | '820OHM'     | '1%'         = 'SMC_0402R_H016'     | '(SMC_0402R_C_H016)'                   | 'RES,820,1%,0.1W,50V,0402,ASR'                                                          | ''        
 'G152-10559-01' | '2.7KOHM'    | '1%'         = 'SMC_0402R_H016'     | '(SMC_0402R_C_H016)'                   | 'RES,2.7K,1%,0.1W,50V,0402,ASR'                                                         | ''        
 'G152-10560-01' | '523OHM'     | '1%'         = 'SMC_0402R_H016'     | '(SMC_0402R_C_H016)'                   | 'RES,523,1%,0.1W,50V,0402,ASR'                                                          | ''        
 'G152-10561-01' | '300OHM'     | '1%'         = 'SMC_0402R_H016'     | '(SMC_0402R_C_H016)'                   | 'RES,300,1%,0.1W,50V,0402,ASR'                                                          | ''        
 'G152-10562-01' | '26.7KOHM'   | '1%'         = 'SMC_0402R_H016'     | '(SMC_0402R_C_H016)'                   | 'RES,26.7K,1%,0.1W,50V,0402,ASR'                                                        | ''        
 'G152-10563-01' | '2.49KOHM'   | '1%'         = 'SMC_0402R_H016'     | '(SMC_0402R_C_H016)'                   | 'RES,2.49K,1%,0.1W,50V,0402,ASR'                                                        | ''        
 'G152-10564-01' | '2.37KOHM'   | '1%'         = 'SMC_0402R_H016'     | '(SMC_0402R_C_H016)'                   | 'RES,2.37K,1%,0.1W,50V,0402,ASR'                                                        | ''        
 'G152-10565-01' | '2.21KOHM'   | '1%'         = 'SMC_0402R_H016'     | '(SMC_0402R_C_H016)'                   | 'RES,2.21K,1%,0.1W,50V,0402,ASR'                                                        | ''        
 'G152-10566-01' | '22KOHM'     | '1%'         = 'SMC_0402R_H016'     | '(SMC_0402R_C_H016)'                   | 'RES,22K,1%,0.1W,50V,0402,ASR'                                                          | ''        
 'G152-10577-01' | '768OHM'     | '1%'         = 'SMC_0603R_H022'     | '(SMC_0603R_H022)'                     | 'RES,768,1%,0.1W,75V,0603,ASR'                                                          | ''        
 'G152-10578-01' | '44.2KOHM'   | '1%'         = 'SMC_0603R_H022'     | '(SMC_0603R_H022)'                     | 'RES,44.2K,1%,0.1W,75V,0603,ASR'                                                        | ''        
 'G152-10579-01' | '165OHM'     | '1%'         = 'SMC_0603R_H022'     | '(SMC_0603R_H022)'                     | 'RES,165,1%,0.1W,75V,0603,ASR'                                                          | ''        
 'G152-10580-01' | '75OHM'      | '1%'         = 'SMC_0603R_H022'     | '(SMC_0603R_H022)'                     | 'RES,75,1%,0.1W,75V,0603,ASR'                                                           | ''        
 'G152-10581-01' | '49.9OHM'    | '1%'         = 'SMC_0603R_H022'     | '(SMC_0603R_H022)'                     | 'RES,49.9,1%,0.1W,75V,0603,ASR'                                                         | ''        
 'G152-10567-01' | '1.8KOHM'    | '1%'         = 'SMC_0402R_H016'     | '(SMC_0402R_C_H016)'                   | 'RES,1.8K,1%,0.1W,50V,0402,ASR'                                                         | ''        
 'G152-10568-01' | '17.8KOHM'   | '1%'         = 'SMC_0402R_H016'     | '(SMC_0402R_C_H016)'                   | 'RES,17.8K,1%,0.1W,50V,0402,ASR'                                                        | ''        
 'G152-10569-01' | '1.69KOHM'   | '1%'         = 'SMC_0402R_H016'     | '(SMC_0402R_C_H016)'                   | 'RES,1.69K,1%,0.1W,50V,0402,ASR'                                                        | ''        
 'G152-10570-01' | '162OHM'     | '1%'         = 'SMC_0402R_H016'     | '(SMC_0402R_C_H016)'                   | 'RES,162,1%,0.1W,50V,0402,ASR'                                                          | ''        
 'G152-10571-01' | '1.43KOHM'   | '1%'         = 'SMC_0402R_H016'     | '(SMC_0402R_C_H016)'                   | 'RES,1.43K,1%,0.1W,50V,0402,ASR'                                                        | ''        
 'G152-10572-01' | '13.3KOHM'   | '1%'         = 'SMC_0402R_H016'     | '(SMC_0402R_C_H016)'                   | 'RES,13.3K,1%,0.1W,50V,0402,ASR'                                                        | ''        
 'G152-10573-01' | '120KOHM'    | '1%'         = 'SMC_0402R_H016'     | '(SMC_0402R_C_H016)'                   | 'RES,120K,1%,0.1W,50V,0402,ASR'                                                         | ''        
 'G152-10574-01' | '12KOHM'     | '1%'         = 'SMC_0402R_H016'     | '(SMC_0402R_C_H016)'                   | 'RES,12K,1%,0.1W,50V,0402,ASR'                                                          | ''        
 'G152-10575-01' | '56OHM'      | '1%'         = 'SMC_0402R_H016'     | '(SMC_0402R_C_H016)'                   | 'RES,56,1%,0.1W,50V,0402,ASR'                                                           | ''        
 'G152-10576-01' | '59OHM'      | '1%'         = 'SMC_0402R_H016'     | '(SMC_0402R_C_H016)'                   | 'RES,59,1%,0.1W,50V,0402,ASR'                                                           | ''        
 'G152-10582-01' | '8.66KOHM'   | '1%'         = 'SMC_0402R_H016'     | '(SMC_0402R_C_H016)'                   | 'RES,8.66K,1%,0.1W,50V,0402,ASR'                                                        | ''        
 'G152-10583-01' | '7.5KOHM'    | '1%'         = 'SMC_0402R_H016'     | '(SMC_0402R_C_H016)'                   | 'RES,7.5K,1%,0.1W,50V,0402,ASR'                                                         | ''        
 'G152-10584-01' | '680OHM'     | '1%'         = 'SMC_0402R_H016'     | '(SMC_0402R_C_H016)'                   | 'RES,680,1%,0.1W,50V,0402,ASR'                                                          | ''        
 'G152-10585-01' | '499OHM'     | '1%'         = 'SMC_0402R_H016'     | '(SMC_0402R_C_H016)'                   | 'RES,499,1%,0.1W,50V,0402,ASR'                                                          | ''        
 'G152-10586-01' | '4.64KOHM'   | '1%'         = 'SMC_0402R_H016'     | '(SMC_0402R_C_H016)'                   | 'RES,4.64K,1%,0.1W,50V,0402,ASR'                                                        | ''        
 'G152-10587-01' | '45.3KOHM'   | '1%'         = 'SMC_0402R_H016'     | '(SMC_0402R_C_H016)'                   | 'RES,45.3K,1%,0.1W,50V,0402,ASR'                                                        | ''        
 'G152-10588-01' | '4.12KOHM'   | '1%'         = 'SMC_0402R_H016'     | '(SMC_0402R_C_H016)'                   | 'RES,4.12K,1%,0.1W,50V,0402,ASR'                                                        | ''        
 'G152-10589-01' | '412OHM'     | '1%'         = 'SMC_0402R_H016'     | '(SMC_0402R_C_H016)'                   | 'RES,412,1%,0.1W,50V,0402,ASR'                                                          | ''        
 'G152-10590-01' | '39KOHM'     | '1%'         = 'SMC_0402R_H016'     | '(SMC_0402R_C_H016)'                   | 'RES,39K,1%,0.1W,50V,0402,ASR'                                                          | ''        
 'G152-10591-01' | '316KOHM'    | '1%'         = 'SMC_0402R_H016'     | '(SMC_0402R_C_H016)'                   | 'RES,316K,1%,0.1W,50V,0402,ASR'                                                         | ''        
 'G152-10592-01' | '3.01KOHM'   | '1%'         = 'SMC_0402R_H016'     | '(SMC_0402R_C_H016)'                   | 'RES,3.01K,1%,0.1W,50V,0402,ASR'                                                        | ''        
 'G152-10593-01' | '3KOHM'      | '1%'         = 'SMC_0402R_H016'     | '(SMC_0402R_C_H016)'                   | 'RES,3K,1%,0.1W,50V,0402,ASR'                                                           | ''        
 'G152-10594-01' | '5.1KOHM'    | '1%'         = 'SMC_0402R_H016'     | '(SMC_0402R_C_H016)'                   | 'RES,5.1K,1%,0.1W,50V,0402,ASR'                                                         | ''        
 'G152-10595-01' | '430OHM'     | '1%'         = 'SMC_0402R_H016'     | '(SMC_0402R_C_H016)'                   | 'RES,430,1%,0.1W,75V,0402,ASR'                                                          | ''        
 'G152-10596-01' | '73.2KOHM'   | '0.5%'       = 'SMC_0402R_H016'     | '(SMC_0402R_C_H016)'                   | 'RES,73.2K,0.5%,0.1W,50V,0402,ASR'                                                      | ''        
 'G152-10597-01' | '0.68OHM'    | '1%'         = 'SMC_1206R_H028'     | '(SMC_1206R_H028)'                     | 'RES,0.68,1%,0.33W,1206,ASR'                                                            | ''        
 'G152-10598-01' | '27.4KOHM'   | '0.5%'       = 'SMC_0201R_H010'     | '(SMC_0201R_C_H010)'                   | 'RES,27.4K,0.5%,0.05W,0201'                                                             | ''        
 'G155-01913-01' | '191KOHM'    | '1%'         = 'SMC_0402R_H016'     | '(SMC_0402R_C_H016)'                   | 'RES,191K,1%,0.063W,0402'                                                               | ''        
 'G152-10599-01' | '0.002OHM'   | '1%'         = 'SMC_2512R_H033'     | '(SMC_2512R_H033)'                     | 'RES,0.002,1%,2W,2512'                                                                  | 'PREFER'  
 'G155-11002-Z1' | '10KOHM'     | '0.1%'       = 'SMC_0402R_H016'     | '(SMC_0402R_C_H016)'                   | 'RES,10K,0.1%,0.0625W,0402'                                                             | 'PREFER'  
 'G155-14992-Z1' | '49.9KOHM'   | '0.1%'       = 'SMC_0402R_H016'     | '(SMC_0402R_C_H016)'                   | 'RES,49.9K,0.1%,0.0625W,0402'                                                           | 'PREFER'  
 'G155-12212-Z1' | '22.1KOHM'   | '0.1%'       = 'SMC_0402R_H016'     | '(SMC_0402R_C_H016)'                   | 'RES,22.1K,0.1%,0.0625W,0402'                                                           | 'PREFER'  
 'G155-14991-Z1' | '4.99KOHM'   | '0.1%'       = 'SMC_0402R_H016'     | '(SMC_0402R_C_H016)'                   | 'RES,4.99K,0.1%,0.0625W,0402'                                                           | 'PREFER'  
 'G155-11001-Z1' | '1KOHM'      | '0.1%'       = 'SMC_0402R_H016'     | '(SMC_0402R_C_H016)'                   | 'RES,1K,0.1%,0.0625W,0402'                                                              | 'PREFER'  
 'G152-10600-01' | '0.001OHM'   | '1%'         = 'SMC_2512R_H035'     | '(SMC_2512R_H035)'                     | 'RES,0.001,1%,2W,2512'                                                                  | 'PREFER'  
 'G157-12R20-01' | '2.2OHM'     | '1%'         = 'SMC_0805R_H026'     | '(SMC_0805R_H026)'                     | 'RES,2.2,1%,0.125W,0805'                                                                | 'PREFER'  
 'G155-11002-01' | '10KOHM'     | '1%'         = 'SMC_0402R_H016'     | '(SMC_0402R_C_H016)'                   | 'RES,10K,1%,0.0625W,0402'                                                               | 'PREFER'  
 'G155-12201-01' | '2.2KOHM'    | '1%'         = 'SMC_0402R_H016'     | '(SMC_0402R_C_H016)'                   | 'RES,2.2K,1%0.0625W,0402'                                                               | 'PREFER'  
 'G155-12001-01' | '2KOHM'      | '1%'         = 'SMC_0402R_H016'     | '(SMC_0402R_C_H016)'                   | 'RES,2K,1%,0.0625W,0402'                                                                | 'PREFER'  
 'G155-12002-01' | '20KOHM'     | '1%'         = 'SMC_0402R_H016'     | '(SMC_0402R_C_H016)'                   | 'RES,20K,1%,0.0625W,0402'                                                               | 'PREFER'  
 'G155-120R0-01' | '20OHM'      | '1%'         = 'SMC_0402R_H016'     | '(SMC_0402R_C_H016)'                   | 'RES,20,1%,0.0625W,0402'                                                                | 'PREFER'  
 'G155-122R0-01' | '22OHM'      | '1%'         = 'SMC_0402R_H016'     | '(SMC_0402R_C_H016)'                   | 'RES,22,1%,0.0625W,0402'                                                                | 'PREFER'  
 'G155-11004-01' | '1MOHM'      | '1%'         = 'SMC_0402R_H016'     | '(SMC_0402R_C_H016)'                   | 'RES,1M,1%,0.0625W,0402'                                                                | 'PREFER'  
 'G155-13601-01' | '3.6KOHM'    | '1%'         = 'SMC_0402R_H016'     | '(SMC_0402R_C_H016)'                   | 'RES,3.6K,1%,0.0625W,0402'                                                              | 'PREFER'  
 'G155-11000-01' | '100OHM'     | '1%'         = 'SMC_0402R_H016'     | '(SMC_0402R_C_H016)'                   | 'RES,100,1%,0.0625W,0402'                                                               | 'PREFER'  
 'G155-11001-01' | '1KOHM'      | '1%'         = 'SMC_0402R_H016'     | '(SMC_0402R_C_H016)'                   | 'RES,1K,1%,0.0625W,0402'                                                                | 'PREFER'  
 'G155-12400-01' | '240OHM'     | '1%'         = 'SMC_0402R_H016'     | '(SMC_0402R_C_H016)'                   | 'RES,240,1%,0.0625W,0402'                                                               | 'PREFER'  
 'G155-11200-01' | '120OHM'     | '1%'         = 'SMC_0402R_H016'     | '(SMC_0402R_C_H016)'                   | 'RES,120,1%,0.0625W,0402'                                                               | 'PREFER'  
 'G156-11002-01' | '10KOHM'     | '1%'         = 'SMC_0603R_H024'     | '(SMC_0603R_H024)'                     | 'RES,10K,1%,0.1W,0603'                                                                  | 'PREFER'  
 'G155-11500-01' | '150OHM'     | '1%'         = 'SMC_0402R_H016'     | '(SMC_0402R_C_H016)'                   | 'RES,150,1%,0.0625W,0402'                                                               | 'PREFER'  
 'G156-11001-01' | '1KOHM'      | '1%'         = 'SMC_0603R_H024'     | '(SMC_0603R_H024)'                     | 'RES,1K,1%,0.1W,0603'                                                                   | 'PREFER'  
 'G156-11500-01' | '150OHM'     | '1%'         = 'SMC_0603R_H024'     | '(SMC_0603R_H024)'                     | 'RES,150,1%,0.1W,0603'                                                                  | 'PREFER'  
 'G155-11501-01' | '1.5KOHM'    | '1%'         = 'SMC_0402R_H016'     | '(SMC_0402R_C_H016)'                   | 'RES,1.5K,1%,0.0625W,0402'                                                              | 'PREFER'  
 'G155-11502-01' | '15KOHM'     | '1%'         = 'SMC_0402R_H016'     | '(SMC_0402R_C_H016)'                   | 'RES,15K,1%,0.0625W,0402'                                                               | 'PREFER'  
 'G155-12000-01' | '200OHM'     | '1%'         = 'SMC_0402R_H016'     | '(SMC_0402R_C_H016)'                   | 'RES,200,1%,0.0625W,0402'                                                               | 'PREFER'  
 'G155-13300-01' | '330OHM'     | '1%'         = 'SMC_0402R_H016'     | '(SMC_0402R_C_H016)'                   | 'RES,330,1%,0.0625W,0402'                                                               | 'PREFER'  
 'G155-13301-01' | '3.3KOHM'    | '1%'         = 'SMC_0402R_H016'     | '(SMC_0402R_C_H016)'                   | 'RES,3.3K,1%,0.0625W,0402'                                                              | 'PREFER'  
 'G155-133R0-01' | '33OHM'      | '1%'         = 'SMC_0402R_H016'     | '(SMC_0402R_C_H016)'                   | 'RES,33,1%,0.0625W,0402'                                                                | 'PREFER'  
 'G156-11000-01' | '100OHM'     | '1%'         = 'SMC_0603R_H024'     | '(SMC_0603R_H024)'                     | 'RES,100,1%,0.1W,0603'                                                                  | 'PREFER'  
 'G155-149R9-01' | '49.9OHM'    | '1%'         = 'SMC_0402R_H016'     | '(SMC_0402R_C_H016)'                   | 'RES,49.9,1%,0.0625W,0402'                                                              | 'PREFER'  
 'G155-110R0-01' | '10OHM'      | '1%'         = 'SMC_0402R_H016'     | '(SMC_0402R_C_H016)'                   | 'RES,10,1%,0.0625W,0402'                                                                | 'PREFER'  
 'G155-14701-01' | '4.7KOHM'    | '1%'         = 'SMC_0402R_H016'     | '(SMC_0402R_C_H016)'                   | 'RES,4.7K,1%,0.0625W,0402'                                                              | 'PREFER'  
 'G155-14991-01' | '4.99KOHM'   | '1%'         = 'SMC_0402R_H016'     | '(SMC_0402R_C_H016)'                   | 'RES,4.99K,1%,0.0625W,0402'                                                             | 'PREFER'  
 'G156-110R0-01' | '10OHM'      | '1%'         = 'SMC_0603R_H024'     | '(SMC_0603R_H024)'                     | 'RES,10,1%,0.1W,0603'                                                                   | 'PREFER'  
 'G156-12R20-01' | '2.2OHM'     | '1%'         = 'SMC_0603R_H024'     | '(SMC_0603R_H024)'                     | 'RES,2.2,1%,0.1W,0603'                                                                  | 'PREFER'  
 'G155-11003-01' | '100KOHM'    | '1%'         = 'SMC_0402R_H016'     | '(SMC_0402R_C_H016)'                   | 'RES,100K,1%,0.0625W,0402'                                                              | 'PREFER'  
 'G155-11R00-01' | '1OHM'       | '1%'         = 'SMC_0402R_H016'     | '(SMC_0402R_C_H016)'                   | 'RES,1,1%,0.0625W,0402'                                                                 | 'PREFER'  
 'G155-100R0-J0' | '0OHM'       | '-'          = 'SMC_0402R_H016'     | '(SMC_0402R_C_H016,C0402-0P8MM-45DG)'                   | 'RES,0,JUMPER,0.0625W,0402'                                                             | 'PREFER'  
 'G156-100R0-J0' | '0OHM'       | '-'          = 'SMC_0603R_H024'     | '(SMC_0603R_H024)'                     | 'RES,0,JUMPER,0.1W,0603'                                                                | 'PREFER'  
 'G157-100R0-J0' | '0OHM'       | '-'          = 'SMC_0805R_H026'     | '(SMC_0805R_H026)'                     | 'RES,0,JUMPER,0.125W,0805'                                                              | 'PREFER'  
 'G155-08202-Z1' | '82KOHM'     | '0.1%'       = 'SMC_0402R_H014'     | '(SMC_0402R_C_H014)'                   | 'RES,82KOHM,0.1%,1/16W,0402'                                                            | ''        
 'G155-04122-Z1' | '41.2KOHM'   | '0.1%'       = 'SMC_0402R_H014'     | '(SMC_0402R_C_H014)'                   | 'RES,41.2KOHM,0.1%,1/16W,0402'                                                          | ''        
 'G155-01743-Z1' | '174KOHM'    | '0.1%'       = 'SMC_0402R_H014'     | '(SMC_0402R_C_H014)'                   | 'RES,174KOHM,0.1%,1/16W,0402'                                                           | ''        
 'G155-093R1-01' | '93.1OHM'    | '1%'         = 'SMC_0402R_H016'     | '(SMC_0402R_C_H016)'                   | 'RES,93.1OHM,1%,1/16W,0402'                                                             | ''        
 'G155-01022-Z1' | '10.2KOHM'   | '0.1%'       = 'SMC_0402R_H014'     | '(SMC_0402R_C_H014)'                   | 'RES,10.2K,0.1%,1/16W,0402'                                                             | ''        
 'G155-05602-01' | '56KOHM'     | '1%'         = 'SMC_0402R_H016'     | '(SMC_0402R_C_H016)'                   | 'RES,56K,1%,1/16W,0402'                                                                 | ''        
 'G155-06803-01' | '680KOHM'    | '1%'         = 'SMC_0402R_H016'     | '(SMC_0402R_C_H016,SMC_0402R_V2_H016)' | 'RES,680K,1%,0.063W,0402'                                                               | ''        
 'G155-01783-01' | '178KOHM'    | '1%'         = 'SMC_0402R_H016'     | '(SMC_0402R_C_H016)'                   | 'RES,178K,1%,0.063W,0402'                                                               | ''        
 'G152-10601-01' | '0OHM'       | '-'          = 'SMC_0201R_H010'     | '(SMC_0201R_C_H010)'                   | 'RES,0,JUMPER,0.5A,0201,ASR,-55C~125C'                                                  | ''        
 'G152-10602-01' | '4.75KOHM'   | '1%'         = 'SMC_0402R_H016'     | '(SMC_0402R_C_H016)'                   | 'RES,4.75K,1%,0.1W,50V,0402,ASR'                                                        | ''        
 'G152-10603-01' | '121KOHM'    | '1%'         = 'SMC_0402R_H016'     | '(SMC_0402R_C_H016)'                   | 'RES,121K,1%,0.1W,50V,200PPM,0402,ASR'                                                  | ''        
 'G152-10605-01' | '6.04KOHM'   | '0.5%'       = 'SMC_0402R_H016'     | '(SMC_0402R_C_H016)'                   | 'RES,6.04K,0.5%,0.063W,50V,0402'                                                        | ''        
 'G152-10604-01' | '4.7KOHM'    | '1%'         = 'SMC_0201R_H010'     | '(SMC_0201R_C_H010)'                   | 'RES,4.7K,1%,0.05W,25V,-55C~125C,0201,ASR'                                              | ''        
 'G152-10606-01' | '18KOHM'     | '1%'         = 'SMC_0402R_H016'     | '(SMC_0402R_C_H016)'                   | 'RES,18K,1%,0.1W,50V,200PPM,0402,ASR'                                                   | ''        
 'G152-10607-01' | '390KOHM'    | '1%'         = 'SMC_0402R_H016'     | '(SMC_0402R_C_H016)'                   | 'RES,390K,1%,0.1W,50V,200PPM,0402,ASR'                                                  | ''        
 'G152-10608-01' | '422KOHM'    | '1%'         = 'SMC_0402R_H016'     | '(SMC_0402R_C_H016)'                   | 'RES,422K,1%,0.1W,50V,200PPM,0402,ASR'                                                  | ''        
 'G152-10609-01' | '453KOHM'    | '1%'         = 'SMC_0402R_H016'     | '(SMC_0402R_C_H016)'                   | 'RES,453K,1%,0.1W,50V,200PPM,0402,ASR'                                                  | ''        
 'G152-10610-01' | '60.4OHM'    | '1%'         = 'SMC_0402R_H016'     | '(SMC_0402R_C_H016)'                   | 'RES,60.4,1%,0.1W,50V,200PPM,0402,ASR'                                                  | ''        
 'G152-10611-01' | '220OHM'     | '1%'         = 'SMC_0603R_H022'     | '(SMC_0603R_H022)'                     | 'RES,220,1%,0.1W,75V,0603,ASR'                                                          | ''        
 'G152-10612-01' | '91KOHM'     | '1%'         = 'SMC_0402R_H016'     | '(SMC_0402R_C_H016)'                   | 'RES,91K,1%,0.1W,50V,200PPM,0402,ASR'                                                   | ''        
 'G155-04222-01' | '42.2KOHM'   | '1%'         = 'SMC_0402R_H016'     | '(SMC_0402R_C_H016)'                   | '	RES,42.2K,1%,0.063W,0402'                                                            | 'NFND'        
 'A152-10278-IB' | '0.0005OHM'  | '1%'         = 'SMC_R_394X205_H058' | '(SMC_R_394X205_H058)'                 | 'RES,0.0005OHM,1%,3W,3921'                                                              | ''        
 'G152-10613-01' | '330OHM'     | '1%'         = 'SMC_0603R_H022'     | '(SMC_0603R_H022)'                     | 'RES,330,1%,0.1W,75V,0603,ASR'                                                          | ''        
 'G152-10614-01' | '200OHM'     | '1%'         = 'SMC_0603R_H022'     | '(SMC_0603R_H022)'                     | 'RES,200,1%,0.1W,75V,0603,ASR'                                                          | ''        
 'G152-10615-01' | '14.7OHM'    | '1%'         = 'SMC_0402R_H016'     | '(SMC_0402R_C_H016)'                   | 'RES,14.7,1%,0.1W,50V,200PPM,0402,ASR'                                                  | ''        
 'G152-10616-01' | '10OHM'      | '5%'         = 'SMC_1206R_H028'     | '(SMC_1206R_H028)'                     | 'RES,10,5%,0.25W,1206,ASR'                                                              | ''        
 'G152-10617-01' | '100OHM'     | '0.1%'       = 'SMC_0402R_H016'     | '(SMC_0402R_C_H016)'                   | 'RES,100,0.1%,0.063W,0402'                                                              | ''        
 'G152-10365-01' | '24KOHM'     | '0.1%'       = 'SMC_0402R_H016'     | '(SMC_0402R_C_H016)'                   | 'RES,24K,0.1%,0.0625W,0402'                                                             | ''        
 'G152-10268-01' | '5.1KOHM'    | '0.1%'       = 'SMC_0402R_H016'     | '(SMC_0402R_C_H016)'                   | 'RES,5.1K,0.1%,0.063W,0402'                                                             | ''        
 'A152-10456-IB' | '1KOHM'      | '1%'         = 'SMC_0402R_H016'     | '(SMC_0402R_C_H016)'                   | 'RES,1K,1%,0.063W,50V,0402,ASR'                                                         | ''        
 'G152-10618-01' | '180KOHM'    | '0.1%'       = 'SMC_0402R_H016'     | '(SMC_0402R_C_H016)'                   | 'RES,180K,0.1%,0.0625W,0402'                                                            | 'REJECT'        
 'G155-01803-Z1' | '180KOHM'    | '0.1%'       = 'SMC_0402R_H016'     | '(SMC_0402R_C_H016)'                   | 'RES,180K,0.1%,0.0625W,0402'                                                            | ''        
 'G155-07R50-01' | '7.5OHM'     | '1%'         = 'SMC_0402R_H016'     | '(SMC_0402R_C_H016)'                   | 'RES,7.5OHM,1%,0.063W,-200 TO 400PPM/C,0402'                                            | ''        
 'A152-04R99-HT' | '4.99OHM'    | '0.1%'       = 'SMC_0805R_H026'     | '(SMC_0805R_H026)'                     | 'RES,4.99OHM,0.1%,0.125W,0805'                                                          | ''        
 'R155-04751-Z1' | '4.75KOHM'   | '0.1%'       = 'SMC_0402R_H016'     | '(SMC_0402R_C_H016)'                   | 'RES,4.75K,0.1%,0.0625W,0402,50TCR'                                                     | 'REJECT'        
 'G155-04751-Z1' | '4.75KOHM'   | '0.1%'       = 'SMC_0402R_H016'     | '(SMC_0402R_C_H016)'                   | 'RES,4.75K,0.1%,0.0625W,0402,50TCR'                                                     | ''        

END_PART

END.

